FILE_TYPE = MACRO_DRAWING;
SET COLOR_WIRE YELLOW;
SET COLOR_PROP ORANGE;
SET COLOR_DOT WHITE;
SET COLOR_ARC YELLOW;
SET COLOR_BODY GREEN;
SET COLOR_NOTE PURPLE;
SET PROP_DISPLAY VALUE;
SET PAGE_NUMBER P89;
FORCEADD UNIVERSAL_GND..1
(-2125 -175);
FORCEPROP 3 LASTPIN (-2125 -125) SIG_NAME GND\g
J 0
(-2115 -115);
DISPLAY 0.659574 (-2115 -115);
PAINT MONO (-2115 -115);
DISPLAY INVISIBLE (-2115 -115);
FORCEPROP 2 LAST CDS_LIB logical_power
J 0
(-2125 -175);
PAINT MONO (-2125 -175);
DISPLAY INVISIBLE (-2125 -175);
FORCEPROP 1 LAST HDL_POWER GND
J 1
(-2100 -250);
DISPLAY 0.872340 (-2100 -250);
PAINT GREEN (-2100 -250);
DISPLAY INVISIBLE (-2100 -250);
FORCEPROP 1 LAST PATH I1
J 0
(-2050 -175);
DISPLAY 0.872340 (-2050 -175);
PAINT AQUA (-2050 -175);
DISPLAY INVISIBLE (-2050 -175);
FORCEADD OFFPAGE..1
(-3300 1950);
FORCEPROP 2 LAST $XR3 88 
J 0
(-3672 1914);
DISPLAY 0.638298 (-3672 1914);
PAINT MONO (-3672 1914);
FORCEPROP 2 LAST $XR2 87 
J 0
(-3582 1914);
DISPLAY 0.638298 (-3582 1914);
PAINT MONO (-3582 1914);
FORCEPROP 2 LAST $XR1 86 
J 0
(-3672 1950);
DISPLAY 0.638298 (-3672 1950);
PAINT MONO (-3672 1950);
FORCEPROP 2 LAST $XR0 129 
J 0
(-3582 1950);
DISPLAY 0.638298 (-3582 1950);
PAINT MONO (-3582 1950);
FORCEPROP 2 LAST CDS_LIB standard
J 0
(-3300 1950);
PAINT MONO (-3300 1950);
DISPLAY INVISIBLE (-3300 1950);
FORCEPROP 1 LAST OFFPAGE TRUE
J 0
(-2975 1825);
DISPLAY 0.872340 (-2975 1825);
DISPLAY INVISIBLE (-2975 1825);
FORCEPROP 1 LAST COMMENT_BODY TRUE
J 0
(-3175 1850);
DISPLAY 0.872340 (-3175 1850);
PAINT GREEN (-3175 1850);
DISPLAY INVISIBLE (-3175 1850);
FORCEPROP 2 LAST PATH I10
J 0
(-3250 2025);
DISPLAY 1.021277 (-3250 2025);
DISPLAY INVISIBLE (-3250 2025);
FORCEADD TAP..1
(-700 3500);
FORCEPROP 3 LASTPIN (-750 3500) SIG_NAME M_D_CPU0_SA_DQ<17>
J 0
(-740 3510);
DISPLAY 0.659574 (-740 3510);
PAINT MONO (-740 3510);
DISPLAY INVISIBLE (-740 3510);
FORCEPROP 1 LASTPIN (-750 3500) BN 17
J 0
(-762 3508);
DISPLAY 0.680851 (-762 3508);
PAINT GREEN (-762 3508);
FORCEPROP 2 LAST CDS_LIB standard
J 0
(-700 3500);
PAINT MONO (-700 3500);
DISPLAY INVISIBLE (-700 3500);
FORCEPROP 1 LAST BODY_TYPE PLUMBING
J 0
(-700 3550);
DISPLAY 0.872340 (-700 3550);
PAINT GREEN (-700 3550);
DISPLAY INVISIBLE (-700 3550);
FORCEPROP 1 LAST HDL_TAP TRUE
J 0
(-375 3375);
DISPLAY 0.872340 (-375 3375);
DISPLAY INVISIBLE (-375 3375);
FORCEPROP 1 LAST PATH I100
J 0
(-702 3500);
DISPLAY 0.872340 (-702 3500);
PAINT GREEN (-702 3500);
DISPLAY INVISIBLE (-702 3500);
FORCEADD TAP..1
(-700 3550);
FORCEPROP 3 LASTPIN (-750 3550) SIG_NAME M_D_CPU0_SA_DQ<18>
J 0
(-740 3560);
DISPLAY 0.659574 (-740 3560);
PAINT MONO (-740 3560);
DISPLAY INVISIBLE (-740 3560);
FORCEPROP 1 LASTPIN (-750 3550) BN 18
J 0
(-762 3558);
DISPLAY 0.680851 (-762 3558);
PAINT GREEN (-762 3558);
FORCEPROP 2 LAST CDS_LIB standard
J 0
(-700 3550);
PAINT MONO (-700 3550);
DISPLAY INVISIBLE (-700 3550);
FORCEPROP 1 LAST BODY_TYPE PLUMBING
J 0
(-700 3600);
DISPLAY 0.872340 (-700 3600);
PAINT GREEN (-700 3600);
DISPLAY INVISIBLE (-700 3600);
FORCEPROP 1 LAST HDL_TAP TRUE
J 0
(-375 3425);
DISPLAY 0.872340 (-375 3425);
DISPLAY INVISIBLE (-375 3425);
FORCEPROP 1 LAST PATH I101
J 0
(-702 3550);
DISPLAY 0.872340 (-702 3550);
PAINT GREEN (-702 3550);
DISPLAY INVISIBLE (-702 3550);
FORCEADD TAP..1
(-700 3600);
FORCEPROP 3 LASTPIN (-750 3600) SIG_NAME M_D_CPU0_SA_DQ<19>
J 0
(-740 3610);
DISPLAY 0.659574 (-740 3610);
PAINT MONO (-740 3610);
DISPLAY INVISIBLE (-740 3610);
FORCEPROP 1 LASTPIN (-750 3600) BN 19
J 0
(-762 3608);
DISPLAY 0.680851 (-762 3608);
PAINT GREEN (-762 3608);
FORCEPROP 2 LAST CDS_LIB standard
J 0
(-700 3600);
PAINT MONO (-700 3600);
DISPLAY INVISIBLE (-700 3600);
FORCEPROP 1 LAST BODY_TYPE PLUMBING
J 0
(-700 3650);
DISPLAY 0.872340 (-700 3650);
PAINT GREEN (-700 3650);
DISPLAY INVISIBLE (-700 3650);
FORCEPROP 1 LAST HDL_TAP TRUE
J 0
(-375 3475);
DISPLAY 0.872340 (-375 3475);
DISPLAY INVISIBLE (-375 3475);
FORCEPROP 1 LAST PATH I102
J 0
(-702 3600);
DISPLAY 0.872340 (-702 3600);
PAINT GREEN (-702 3600);
DISPLAY INVISIBLE (-702 3600);
FORCEADD TAP..1
(-700 3650);
FORCEPROP 3 LASTPIN (-750 3650) SIG_NAME M_D_CPU0_SA_DQ<20>
J 0
(-740 3660);
DISPLAY 0.659574 (-740 3660);
PAINT MONO (-740 3660);
DISPLAY INVISIBLE (-740 3660);
FORCEPROP 1 LASTPIN (-750 3650) BN 20
J 0
(-762 3658);
DISPLAY 0.680851 (-762 3658);
PAINT GREEN (-762 3658);
FORCEPROP 2 LAST CDS_LIB standard
J 0
(-700 3650);
PAINT MONO (-700 3650);
DISPLAY INVISIBLE (-700 3650);
FORCEPROP 1 LAST BODY_TYPE PLUMBING
J 0
(-700 3700);
DISPLAY 0.872340 (-700 3700);
PAINT GREEN (-700 3700);
DISPLAY INVISIBLE (-700 3700);
FORCEPROP 1 LAST HDL_TAP TRUE
J 0
(-375 3525);
DISPLAY 0.872340 (-375 3525);
DISPLAY INVISIBLE (-375 3525);
FORCEPROP 1 LAST PATH I103
J 0
(-702 3650);
DISPLAY 0.872340 (-702 3650);
PAINT GREEN (-702 3650);
DISPLAY INVISIBLE (-702 3650);
FORCEADD TAP..1
(-700 3700);
FORCEPROP 3 LASTPIN (-750 3700) SIG_NAME M_D_CPU0_SA_DQ<21>
J 0
(-740 3710);
DISPLAY 0.659574 (-740 3710);
PAINT MONO (-740 3710);
DISPLAY INVISIBLE (-740 3710);
FORCEPROP 1 LASTPIN (-750 3700) BN 21
J 0
(-762 3708);
DISPLAY 0.680851 (-762 3708);
PAINT GREEN (-762 3708);
FORCEPROP 2 LAST CDS_LIB standard
J 0
(-700 3700);
PAINT MONO (-700 3700);
DISPLAY INVISIBLE (-700 3700);
FORCEPROP 1 LAST BODY_TYPE PLUMBING
J 0
(-700 3750);
DISPLAY 0.872340 (-700 3750);
PAINT GREEN (-700 3750);
DISPLAY INVISIBLE (-700 3750);
FORCEPROP 1 LAST HDL_TAP TRUE
J 0
(-375 3575);
DISPLAY 0.872340 (-375 3575);
DISPLAY INVISIBLE (-375 3575);
FORCEPROP 1 LAST PATH I104
J 0
(-702 3700);
DISPLAY 0.872340 (-702 3700);
PAINT GREEN (-702 3700);
DISPLAY INVISIBLE (-702 3700);
FORCEADD TAP..1
(-700 3750);
FORCEPROP 3 LASTPIN (-750 3750) SIG_NAME M_D_CPU0_SA_DQ<22>
J 0
(-740 3760);
DISPLAY 0.659574 (-740 3760);
PAINT MONO (-740 3760);
DISPLAY INVISIBLE (-740 3760);
FORCEPROP 1 LASTPIN (-750 3750) BN 22
J 0
(-762 3758);
DISPLAY 0.680851 (-762 3758);
PAINT GREEN (-762 3758);
FORCEPROP 2 LAST CDS_LIB standard
J 0
(-700 3750);
DISPLAY INVISIBLE (-700 3750);
FORCEPROP 1 LAST BODY_TYPE PLUMBING
J 0
(-700 3800);
DISPLAY 0.872340 (-700 3800);
PAINT GREEN (-700 3800);
DISPLAY INVISIBLE (-700 3800);
FORCEPROP 1 LAST HDL_TAP TRUE
J 0
(-375 3625);
DISPLAY 0.872340 (-375 3625);
DISPLAY INVISIBLE (-375 3625);
FORCEPROP 1 LAST PATH I105
J 0
(-702 3750);
DISPLAY 0.872340 (-702 3750);
PAINT GREEN (-702 3750);
DISPLAY INVISIBLE (-702 3750);
FORCEADD TAP..1
(-700 3800);
FORCEPROP 3 LASTPIN (-750 3800) SIG_NAME M_D_CPU0_SA_DQ<23>
J 0
(-740 3810);
DISPLAY 0.659574 (-740 3810);
PAINT MONO (-740 3810);
DISPLAY INVISIBLE (-740 3810);
FORCEPROP 1 LASTPIN (-750 3800) BN 23
J 0
(-762 3808);
DISPLAY 0.680851 (-762 3808);
PAINT GREEN (-762 3808);
FORCEPROP 2 LAST CDS_LIB standard
J 0
(-700 3800);
DISPLAY INVISIBLE (-700 3800);
FORCEPROP 1 LAST BODY_TYPE PLUMBING
J 0
(-700 3850);
DISPLAY 0.872340 (-700 3850);
PAINT GREEN (-700 3850);
DISPLAY INVISIBLE (-700 3850);
FORCEPROP 1 LAST HDL_TAP TRUE
J 0
(-375 3675);
DISPLAY 0.872340 (-375 3675);
DISPLAY INVISIBLE (-375 3675);
FORCEPROP 1 LAST PATH I106
J 0
(-702 3800);
DISPLAY 0.872340 (-702 3800);
PAINT GREEN (-702 3800);
DISPLAY INVISIBLE (-702 3800);
FORCEADD TAP..1
(-700 3900);
FORCEPROP 3 LASTPIN (-750 3900) SIG_NAME M_D_CPU0_SA_DQ<25>
J 0
(-740 3910);
DISPLAY 0.659574 (-740 3910);
PAINT MONO (-740 3910);
DISPLAY INVISIBLE (-740 3910);
FORCEPROP 1 LASTPIN (-750 3900) BN 25
J 0
(-762 3908);
DISPLAY 0.680851 (-762 3908);
PAINT GREEN (-762 3908);
FORCEPROP 2 LAST CDS_LIB standard
J 0
(-700 3900);
DISPLAY INVISIBLE (-700 3900);
FORCEPROP 1 LAST BODY_TYPE PLUMBING
J 0
(-700 3950);
DISPLAY 0.872340 (-700 3950);
PAINT GREEN (-700 3950);
DISPLAY INVISIBLE (-700 3950);
FORCEPROP 1 LAST HDL_TAP TRUE
J 0
(-375 3775);
DISPLAY 0.872340 (-375 3775);
DISPLAY INVISIBLE (-375 3775);
FORCEPROP 1 LAST PATH I107
J 0
(-702 3900);
DISPLAY 0.872340 (-702 3900);
PAINT GREEN (-702 3900);
DISPLAY INVISIBLE (-702 3900);
FORCEADD TAP..1
(-700 3850);
FORCEPROP 3 LASTPIN (-750 3850) SIG_NAME M_D_CPU0_SA_DQ<24>
J 0
(-740 3860);
DISPLAY 0.659574 (-740 3860);
PAINT MONO (-740 3860);
DISPLAY INVISIBLE (-740 3860);
FORCEPROP 1 LASTPIN (-750 3850) BN 24
J 0
(-762 3858);
DISPLAY 0.680851 (-762 3858);
PAINT GREEN (-762 3858);
FORCEPROP 2 LAST CDS_LIB standard
J 0
(-700 3850);
DISPLAY INVISIBLE (-700 3850);
FORCEPROP 1 LAST BODY_TYPE PLUMBING
J 0
(-700 3900);
DISPLAY 0.872340 (-700 3900);
PAINT GREEN (-700 3900);
DISPLAY INVISIBLE (-700 3900);
FORCEPROP 1 LAST HDL_TAP TRUE
J 0
(-375 3725);
DISPLAY 0.872340 (-375 3725);
DISPLAY INVISIBLE (-375 3725);
FORCEPROP 1 LAST PATH I108
J 0
(-702 3850);
DISPLAY 0.872340 (-702 3850);
PAINT GREEN (-702 3850);
DISPLAY INVISIBLE (-702 3850);
FORCEADD TAP..1
(-700 3950);
FORCEPROP 3 LASTPIN (-750 3950) SIG_NAME M_D_CPU0_SA_DQ<26>
J 0
(-740 3960);
DISPLAY 0.659574 (-740 3960);
PAINT MONO (-740 3960);
DISPLAY INVISIBLE (-740 3960);
FORCEPROP 1 LASTPIN (-750 3950) BN 26
J 0
(-762 3958);
DISPLAY 0.680851 (-762 3958);
PAINT GREEN (-762 3958);
FORCEPROP 2 LAST CDS_LIB standard
J 0
(-700 3950);
DISPLAY INVISIBLE (-700 3950);
FORCEPROP 1 LAST BODY_TYPE PLUMBING
J 0
(-700 4000);
DISPLAY 0.872340 (-700 4000);
PAINT GREEN (-700 4000);
DISPLAY INVISIBLE (-700 4000);
FORCEPROP 1 LAST HDL_TAP TRUE
J 0
(-375 3825);
DISPLAY 0.872340 (-375 3825);
DISPLAY INVISIBLE (-375 3825);
FORCEPROP 1 LAST PATH I109
J 0
(-702 3950);
DISPLAY 0.872340 (-702 3950);
PAINT GREEN (-702 3950);
DISPLAY INVISIBLE (-702 3950);
FORCEADD VCC_CORE..1
(-3175 2075);
FORCEPROP 3 LASTPIN (-3175 2025) SIG_NAME P3V3_AUX\g
J 0
(-3165 2035);
DISPLAY 0.659574 (-3165 2035);
PAINT MONO (-3165 2035);
DISPLAY INVISIBLE (-3165 2035);
FORCEPROP 1 LAST HDL_POWER P3V3_AUX
J 1
(-3175 2125);
DISPLAY 1.148936 (-3175 2125);
PAINT GREEN (-3175 2125);
FORCEPROP 2 LAST CDS_LIB logical_power
J 0
(-3175 2075);
PAINT MONO (-3175 2075);
DISPLAY INVISIBLE (-3175 2075);
FORCEPROP 1 LAST PATH I11
J 0
(-3125 2100);
DISPLAY 0.872340 (-3125 2100);
PAINT AQUA (-3125 2100);
DISPLAY INVISIBLE (-3125 2100);
FORCEADD TAP..1
(-700 4000);
FORCEPROP 3 LASTPIN (-750 4000) SIG_NAME M_D_CPU0_SA_DQ<27>
J 0
(-740 4010);
DISPLAY 0.659574 (-740 4010);
PAINT MONO (-740 4010);
DISPLAY INVISIBLE (-740 4010);
FORCEPROP 1 LASTPIN (-750 4000) BN 27
J 0
(-762 4008);
DISPLAY 0.680851 (-762 4008);
PAINT GREEN (-762 4008);
FORCEPROP 2 LAST CDS_LIB standard
J 0
(-700 4000);
DISPLAY INVISIBLE (-700 4000);
FORCEPROP 1 LAST BODY_TYPE PLUMBING
J 0
(-700 4050);
DISPLAY 0.872340 (-700 4050);
PAINT GREEN (-700 4050);
DISPLAY INVISIBLE (-700 4050);
FORCEPROP 1 LAST HDL_TAP TRUE
J 0
(-375 3875);
DISPLAY 0.872340 (-375 3875);
DISPLAY INVISIBLE (-375 3875);
FORCEPROP 1 LAST PATH I110
J 0
(-702 4000);
DISPLAY 0.872340 (-702 4000);
PAINT GREEN (-702 4000);
DISPLAY INVISIBLE (-702 4000);
FORCEADD TAP..1
(-700 4050);
FORCEPROP 3 LASTPIN (-750 4050) SIG_NAME M_D_CPU0_SA_DQ<28>
J 0
(-740 4060);
DISPLAY 0.659574 (-740 4060);
PAINT MONO (-740 4060);
DISPLAY INVISIBLE (-740 4060);
FORCEPROP 1 LASTPIN (-750 4050) BN 28
J 0
(-762 4058);
DISPLAY 0.680851 (-762 4058);
PAINT GREEN (-762 4058);
FORCEPROP 2 LAST CDS_LIB standard
J 0
(-700 4050);
DISPLAY INVISIBLE (-700 4050);
FORCEPROP 1 LAST BODY_TYPE PLUMBING
J 0
(-700 4100);
DISPLAY 0.872340 (-700 4100);
PAINT GREEN (-700 4100);
DISPLAY INVISIBLE (-700 4100);
FORCEPROP 1 LAST HDL_TAP TRUE
J 0
(-375 3925);
DISPLAY 0.872340 (-375 3925);
DISPLAY INVISIBLE (-375 3925);
FORCEPROP 1 LAST PATH I111
J 0
(-702 4050);
DISPLAY 0.872340 (-702 4050);
PAINT GREEN (-702 4050);
DISPLAY INVISIBLE (-702 4050);
FORCEADD OFFPAGE..1
(-3275 4225);
FORCEPROP 2 LAST $XR1 88 
J 0
(-3586 4225);
DISPLAY 0.638298 (-3586 4225);
PAINT MONO (-3586 4225);
FORCEPROP 2 LAST $XR0 23 
J 0
(-3496 4225);
DISPLAY 0.638298 (-3496 4225);
PAINT MONO (-3496 4225);
FORCEPROP 2 LAST CDS_LIB standard
J 0
(-3275 4225);
PAINT MONO (-3275 4225);
DISPLAY INVISIBLE (-3275 4225);
FORCEPROP 1 LAST OFFPAGE TRUE
J 0
(-2950 4100);
DISPLAY 0.872340 (-2950 4100);
DISPLAY INVISIBLE (-2950 4100);
FORCEPROP 1 LAST COMMENT_BODY TRUE
J 0
(-3150 4125);
DISPLAY 0.872340 (-3150 4125);
PAINT GREEN (-3150 4125);
DISPLAY INVISIBLE (-3150 4125);
FORCEPROP 2 LAST PATH I112
J 0
(-3225 4300);
DISPLAY 1.021277 (-3225 4300);
DISPLAY INVISIBLE (-3225 4300);
FORCEADD TAP..1
R 2
(-2350 4100);
FORCEPROP 3 LASTPIN (-2300 4100) SIG_NAME M_D_CPU0_SA_CA<4>
J 0
(-2290 4110);
DISPLAY 0.659574 (-2290 4110);
PAINT MONO (-2290 4110);
DISPLAY INVISIBLE (-2290 4110);
FORCEPROP 1 LASTPIN (-2300 4100) BN 4
J 2
(-2288 4108);
DISPLAY 0.680851 (-2288 4108);
PAINT GREEN (-2288 4108);
FORCEPROP 2 LAST CDS_LIB standard
J 0
(-2350 4100);
DISPLAY INVISIBLE (-2350 4100);
FORCEPROP 1 LAST BODY_TYPE PLUMBING
J 2
(-2350 4150);
DISPLAY 0.872340 (-2350 4150);
PAINT GREEN (-2350 4150);
DISPLAY INVISIBLE (-2350 4150);
FORCEPROP 1 LAST HDL_TAP TRUE
J 2
(-2675 3975);
DISPLAY 0.872340 (-2675 3975);
DISPLAY INVISIBLE (-2675 3975);
FORCEPROP 1 LAST PATH I113
J 2
(-2348 4100);
DISPLAY 0.872340 (-2348 4100);
PAINT GREEN (-2348 4100);
DISPLAY INVISIBLE (-2348 4100);
FORCEADD TAP..1
R 2
(-2350 4150);
FORCEPROP 3 LASTPIN (-2300 4150) SIG_NAME M_D_CPU0_SA_CA<5>
J 0
(-2290 4160);
DISPLAY 0.659574 (-2290 4160);
PAINT MONO (-2290 4160);
DISPLAY INVISIBLE (-2290 4160);
FORCEPROP 1 LASTPIN (-2300 4150) BN 5
J 2
(-2288 4158);
DISPLAY 0.680851 (-2288 4158);
PAINT GREEN (-2288 4158);
FORCEPROP 2 LAST CDS_LIB standard
J 0
(-2350 4150);
DISPLAY INVISIBLE (-2350 4150);
FORCEPROP 1 LAST BODY_TYPE PLUMBING
J 2
(-2350 4200);
DISPLAY 0.872340 (-2350 4200);
PAINT GREEN (-2350 4200);
DISPLAY INVISIBLE (-2350 4200);
FORCEPROP 1 LAST HDL_TAP TRUE
J 2
(-2675 4025);
DISPLAY 0.872340 (-2675 4025);
DISPLAY INVISIBLE (-2675 4025);
FORCEPROP 1 LAST PATH I114
J 2
(-2348 4150);
DISPLAY 0.872340 (-2348 4150);
PAINT GREEN (-2348 4150);
DISPLAY INVISIBLE (-2348 4150);
FORCEADD TAP..1
R 2
(-2350 4200);
FORCEPROP 3 LASTPIN (-2300 4200) SIG_NAME M_D_CPU0_SA_CA<6>
J 0
(-2290 4210);
DISPLAY 0.659574 (-2290 4210);
PAINT MONO (-2290 4210);
DISPLAY INVISIBLE (-2290 4210);
FORCEPROP 1 LASTPIN (-2300 4200) BN 6
J 2
(-2288 4208);
DISPLAY 0.680851 (-2288 4208);
PAINT GREEN (-2288 4208);
FORCEPROP 2 LAST CDS_LIB standard
J 0
(-2350 4200);
DISPLAY INVISIBLE (-2350 4200);
FORCEPROP 1 LAST BODY_TYPE PLUMBING
J 2
(-2350 4250);
DISPLAY 0.872340 (-2350 4250);
PAINT GREEN (-2350 4250);
DISPLAY INVISIBLE (-2350 4250);
FORCEPROP 1 LAST HDL_TAP TRUE
J 2
(-2675 4075);
DISPLAY 0.872340 (-2675 4075);
DISPLAY INVISIBLE (-2675 4075);
FORCEPROP 1 LAST PATH I115
J 2
(-2348 4200);
DISPLAY 0.872340 (-2348 4200);
PAINT GREEN (-2348 4200);
DISPLAY INVISIBLE (-2348 4200);
FORCEADD TAP..1
(-700 4100);
FORCEPROP 3 LASTPIN (-750 4100) SIG_NAME M_D_CPU0_SA_DQ<29>
J 0
(-740 4110);
DISPLAY 0.659574 (-740 4110);
PAINT MONO (-740 4110);
DISPLAY INVISIBLE (-740 4110);
FORCEPROP 1 LASTPIN (-750 4100) BN 29
J 0
(-762 4108);
DISPLAY 0.680851 (-762 4108);
PAINT GREEN (-762 4108);
FORCEPROP 2 LAST CDS_LIB standard
J 0
(-700 4100);
DISPLAY INVISIBLE (-700 4100);
FORCEPROP 1 LAST BODY_TYPE PLUMBING
J 0
(-700 4150);
DISPLAY 0.872340 (-700 4150);
PAINT GREEN (-700 4150);
DISPLAY INVISIBLE (-700 4150);
FORCEPROP 1 LAST HDL_TAP TRUE
J 0
(-375 3975);
DISPLAY 0.872340 (-375 3975);
DISPLAY INVISIBLE (-375 3975);
FORCEPROP 1 LAST PATH I116
J 0
(-702 4100);
DISPLAY 0.872340 (-702 4100);
PAINT GREEN (-702 4100);
DISPLAY INVISIBLE (-702 4100);
FORCEADD TAP..1
(-700 4150);
FORCEPROP 3 LASTPIN (-750 4150) SIG_NAME M_D_CPU0_SA_DQ<30>
J 0
(-740 4160);
DISPLAY 0.659574 (-740 4160);
PAINT MONO (-740 4160);
DISPLAY INVISIBLE (-740 4160);
FORCEPROP 1 LASTPIN (-750 4150) BN 30
J 0
(-762 4158);
DISPLAY 0.680851 (-762 4158);
PAINT GREEN (-762 4158);
FORCEPROP 2 LAST CDS_LIB standard
J 0
(-700 4150);
DISPLAY INVISIBLE (-700 4150);
FORCEPROP 1 LAST BODY_TYPE PLUMBING
J 0
(-700 4200);
DISPLAY 0.872340 (-700 4200);
PAINT GREEN (-700 4200);
DISPLAY INVISIBLE (-700 4200);
FORCEPROP 1 LAST HDL_TAP TRUE
J 0
(-375 4025);
DISPLAY 0.872340 (-375 4025);
DISPLAY INVISIBLE (-375 4025);
FORCEPROP 1 LAST PATH I117
J 0
(-702 4150);
DISPLAY 0.872340 (-702 4150);
PAINT GREEN (-702 4150);
DISPLAY INVISIBLE (-702 4150);
FORCEADD TAP..1
(-700 4200);
FORCEPROP 3 LASTPIN (-750 4200) SIG_NAME M_D_CPU0_SA_DQ<31>
J 0
(-740 4210);
DISPLAY 0.659574 (-740 4210);
PAINT MONO (-740 4210);
DISPLAY INVISIBLE (-740 4210);
FORCEPROP 1 LASTPIN (-750 4200) BN 31
J 0
(-762 4208);
DISPLAY 0.680851 (-762 4208);
PAINT GREEN (-762 4208);
FORCEPROP 2 LAST CDS_LIB standard
J 0
(-700 4200);
DISPLAY INVISIBLE (-700 4200);
FORCEPROP 1 LAST BODY_TYPE PLUMBING
J 0
(-700 4250);
DISPLAY 0.872340 (-700 4250);
PAINT GREEN (-700 4250);
DISPLAY INVISIBLE (-700 4250);
FORCEPROP 1 LAST HDL_TAP TRUE
J 0
(-375 4075);
DISPLAY 0.872340 (-375 4075);
DISPLAY INVISIBLE (-375 4075);
FORCEPROP 1 LAST PATH I118
J 0
(-702 4200);
DISPLAY 0.872340 (-702 4200);
PAINT GREEN (-702 4200);
DISPLAY INVISIBLE (-702 4200);
FORCEADD UNIVERSAL_GND..1
(1025 -50);
FORCEPROP 3 LASTPIN (1025 0) SIG_NAME GND\g
J 0
(1035 10);
DISPLAY 0.659574 (1035 10);
PAINT MONO (1035 10);
DISPLAY INVISIBLE (1035 10);
FORCEPROP 2 LAST CDS_LIB logical_power
J 0
(1025 -50);
PAINT MONO (1025 -50);
DISPLAY INVISIBLE (1025 -50);
FORCEPROP 1 LAST HDL_POWER GND
J 1
(1050 -125);
DISPLAY 0.872340 (1050 -125);
PAINT GREEN (1050 -125);
DISPLAY INVISIBLE (1050 -125);
FORCEPROP 1 LAST PATH I119
J 0
(1100 -50);
DISPLAY 0.872340 (1100 -50);
PAINT AQUA (1100 -50);
DISPLAY INVISIBLE (1100 -50);
FORCEADD TAP..1
R 2
(-2350 2000);
FORCEPROP 3 LASTPIN (-2300 2000) SIG_NAME M_D_CPU0_SB_CB<0>
J 0
(-2290 2010);
DISPLAY 0.659574 (-2290 2010);
PAINT MONO (-2290 2010);
DISPLAY INVISIBLE (-2290 2010);
FORCEPROP 1 LASTPIN (-2300 2000) BN 0
J 2
(-2288 2008);
DISPLAY 0.680851 (-2288 2008);
PAINT GREEN (-2288 2008);
FORCEPROP 2 LAST CDS_LIB standard
J 0
(-2350 2000);
PAINT MONO (-2350 2000);
DISPLAY INVISIBLE (-2350 2000);
FORCEPROP 1 LAST BODY_TYPE PLUMBING
J 2
(-2350 2050);
DISPLAY 0.872340 (-2350 2050);
PAINT GREEN (-2350 2050);
DISPLAY INVISIBLE (-2350 2050);
FORCEPROP 1 LAST HDL_TAP TRUE
J 2
(-2675 1875);
DISPLAY 0.872340 (-2675 1875);
DISPLAY INVISIBLE (-2675 1875);
FORCEPROP 1 LAST PATH I12
J 2
(-2348 2000);
DISPLAY 0.872340 (-2348 2000);
PAINT GREEN (-2348 2000);
DISPLAY INVISIBLE (-2348 2000);
FORCEADD UNIVERSAL_GND..1
(2650 -50);
FORCEPROP 3 LASTPIN (2650 0) SIG_NAME GND\g
J 0
(2660 10);
DISPLAY 0.659574 (2660 10);
PAINT MONO (2660 10);
DISPLAY INVISIBLE (2660 10);
FORCEPROP 2 LAST CDS_LIB logical_power
J 0
(2650 -50);
PAINT MONO (2650 -50);
DISPLAY INVISIBLE (2650 -50);
FORCEPROP 1 LAST HDL_POWER GND
J 1
(2675 -125);
DISPLAY 0.872340 (2675 -125);
PAINT GREEN (2675 -125);
DISPLAY INVISIBLE (2675 -125);
FORCEPROP 1 LAST PATH I120
J 0
(2725 -50);
DISPLAY 0.872340 (2725 -50);
PAINT AQUA (2725 -50);
DISPLAY INVISIBLE (2725 -50);
FORCEADD Q_CAP..1
(1025 325);
FORCEPROP 1 LAST PART_NUMBER CH5221MEB00
J 0
(1075 175);
DISPLAY 0.978723 (1075 175);
DISPLAY INVISIBLE (1075 175);
FORCEPROP 1 LAST PACK_TYPE C0402
J 0
(1075 125);
DISPLAY 0.978723 (1075 125);
FORCEPROP 1 LAST TOLERANCE 20%
J 0
(1075 275);
DISPLAY 0.978723 (1075 275);
FORCEPROP 1 LAST VALUE 2.2UF
J 0
(1075 375);
DISPLAY 0.978723 (1075 375);
FORCEPROP 1 LAST MATERIAL X6S
J 0
(1075 225);
DISPLAY 0.978723 (1075 225);
FORCEPROP 1 LAST VOLTAGE 6.3V
J 0
(1075 325);
DISPLAY 0.978723 (1075 325);
FORCEPROP 1 LAST $LOCATION C23
J 0
(1075 425);
DISPLAY 0.978723 (1075 425);
FORCEPROP 1 LASTPIN (1025 425) $PN 1
J 0
(1035 405);
DISPLAY 0.787234 (1035 405);
FORCEPROP 1 LASTPIN (1025 225) $PN 2
J 0
(1035 205);
DISPLAY 0.787234 (1035 205);
FORCEPROP 2 LAST CDS_LIB pure_quanta
J 0
(1025 325);
PAINT MONO (1025 325);
DISPLAY INVISIBLE (1025 325);
FORCEPROP 2 LAST CDS_LOCATION C23
J 0
(1075 525);
DISPLAY 1.021277 (1075 525);
DISPLAY INVISIBLE (1075 525);
FORCEPROP 2 LAST $SEC 1
J 0
(1075 525);
DISPLAY 0.680851 (1075 525);
PAINT MONO (1075 525);
DISPLAY INVISIBLE (1075 525);
FORCEPROP 2 LAST CDS_SEC 1
J 0
(1075 525);
DISPLAY 1.021277 (1075 525);
DISPLAY INVISIBLE (1075 525);
FORCEPROP 1 LAST PATH I121
J 0
(1075 475);
DISPLAY 0.978723 (1075 475);
PAINT WHITE (1075 475);
DISPLAY INVISIBLE (1075 475);
FORCEADD VCC_CORE..1
(1025 650);
FORCEPROP 3 LASTPIN (1025 600) SIG_NAME P3V3_AUX\g
J 0
(1035 610);
DISPLAY 0.659574 (1035 610);
PAINT MONO (1035 610);
DISPLAY INVISIBLE (1035 610);
FORCEPROP 1 LAST HDL_POWER P3V3_AUX
J 1
(1025 700);
DISPLAY 1.148936 (1025 700);
PAINT GREEN (1025 700);
FORCEPROP 2 LAST CDS_LIB logical_power
J 0
(1025 650);
PAINT MONO (1025 650);
DISPLAY INVISIBLE (1025 650);
FORCEPROP 1 LAST PATH I122
J 0
(1075 675);
DISPLAY 0.872340 (1075 675);
PAINT AQUA (1075 675);
DISPLAY INVISIBLE (1075 675);
FORCEADD OFFPAGE..3
(125 2575);
FORCEPROP 2 LAST $XR1 88 
J 0
(429 2575);
DISPLAY 0.638298 (429 2575);
PAINT MONO (429 2575);
FORCEPROP 2 LAST $XR0 23 
J 0
(339 2575);
DISPLAY 0.638298 (339 2575);
PAINT MONO (339 2575);
FORCEPROP 2 LAST CDS_LIB standard
J 2
(125 2575);
DISPLAY INVISIBLE (125 2575);
FORCEPROP 1 LAST OFFPAGE TRUE
J 0
(450 2450);
DISPLAY 0.872340 (450 2450);
DISPLAY INVISIBLE (450 2450);
FORCEPROP 1 LAST COMMENT_BODY TRUE
J 0
(75 2475);
DISPLAY 0.872340 (75 2475);
PAINT GREEN (75 2475);
DISPLAY INVISIBLE (75 2475);
FORCEPROP 2 LAST PATH I123
J 0
(325 2650);
DISPLAY 1.021277 (325 2650);
DISPLAY INVISIBLE (325 2650);
FORCEADD Q_CAP..1
(2025 325);
FORCEPROP 1 LAST PART_NUMBER CH6103KEA00
J 0
(2075 175);
DISPLAY 0.978723 (2075 175);
DISPLAY INVISIBLE (2075 175);
FORCEPROP 1 LAST MATERIAL X6S
J 0
(2075 225);
DISPLAY 0.978723 (2075 225);
FORCEPROP 1 LAST VALUE 10UF
J 0
(2075 375);
DISPLAY 0.978723 (2075 375);
FORCEPROP 1 LAST TOLERANCE 10%
J 0
(2075 275);
DISPLAY 0.978723 (2075 275);
FORCEPROP 1 LAST PACK_TYPE C0805
J 0
(2075 125);
DISPLAY 0.978723 (2075 125);
FORCEPROP 1 LAST VOLTAGE 16V
J 0
(2075 325);
DISPLAY 0.978723 (2075 325);
FORCEPROP 1 LAST $LOCATION C24
J 0
(2075 425);
DISPLAY 0.978723 (2075 425);
FORCEPROP 1 LASTPIN (2025 425) $PN 1
J 0
(2035 405);
DISPLAY 0.787234 (2035 405);
FORCEPROP 1 LASTPIN (2025 225) $PN 2
J 0
(2035 205);
DISPLAY 0.787234 (2035 205);
FORCEPROP 2 LAST CDS_LIB pure_quanta
J 0
(2025 325);
PAINT MONO (2025 325);
DISPLAY INVISIBLE (2025 325);
FORCEPROP 2 LAST CDS_LOCATION C24
J 0
(2075 525);
DISPLAY 1.021277 (2075 525);
DISPLAY INVISIBLE (2075 525);
FORCEPROP 2 LAST $SEC 1
J 0
(2075 525);
DISPLAY 0.680851 (2075 525);
PAINT MONO (2075 525);
DISPLAY INVISIBLE (2075 525);
FORCEPROP 2 LAST CDS_SEC 1
J 0
(2075 525);
DISPLAY 1.021277 (2075 525);
DISPLAY INVISIBLE (2075 525);
FORCEPROP 1 LAST PATH I125
J 0
(2075 475);
DISPLAY 0.978723 (2075 475);
PAINT WHITE (2075 475);
DISPLAY INVISIBLE (2075 475);
FORCEADD VCC_CORE..1
(2025 650);
FORCEPROP 3 LASTPIN (2025 600) SIG_NAME P12V_S3_AUX_CPU0_NVDIMM\g
J 0
(2035 610);
DISPLAY 0.659574 (2035 610);
PAINT MONO (2035 610);
DISPLAY INVISIBLE (2035 610);
FORCEPROP 1 LAST HDL_POWER P12V_S3_AUX_CPU0_NVDIMM
J 1
(2025 700);
DISPLAY 1.148936 (2025 700);
PAINT GREEN (2025 700);
FORCEPROP 2 LAST CDS_LIB logical_power
J 0
(2025 650);
PAINT MONO (2025 650);
DISPLAY INVISIBLE (2025 650);
FORCEPROP 1 LAST PATH I126
J 0
(2075 675);
DISPLAY 0.872340 (2075 675);
PAINT AQUA (2075 675);
DISPLAY INVISIBLE (2075 675);
FORCEADD Q_CAP..1
(2650 325);
FORCEPROP 1 LAST PART_NUMBER CH6103KEA00
J 0
(2700 175);
DISPLAY 0.978723 (2700 175);
DISPLAY INVISIBLE (2700 175);
FORCEPROP 1 LAST TOLERANCE 10%
J 0
(2700 275);
DISPLAY 0.978723 (2700 275);
FORCEPROP 1 LAST VALUE 10UF
J 0
(2700 375);
DISPLAY 0.978723 (2700 375);
FORCEPROP 1 LAST PACK_TYPE C0805
J 0
(2700 125);
DISPLAY 0.978723 (2700 125);
FORCEPROP 1 LAST MATERIAL X6S
J 0
(2700 225);
DISPLAY 0.978723 (2700 225);
FORCEPROP 1 LAST VOLTAGE 16V
J 0
(2700 325);
DISPLAY 0.978723 (2700 325);
FORCEPROP 1 LAST $LOCATION C25
J 0
(2700 425);
DISPLAY 0.978723 (2700 425);
FORCEPROP 1 LASTPIN (2650 425) $PN 1
J 0
(2660 405);
DISPLAY 0.787234 (2660 405);
FORCEPROP 1 LASTPIN (2650 225) $PN 2
J 0
(2660 205);
DISPLAY 0.787234 (2660 205);
FORCEPROP 2 LAST CDS_LIB pure_quanta
J 0
(2650 325);
PAINT MONO (2650 325);
DISPLAY INVISIBLE (2650 325);
FORCEPROP 2 LAST CDS_LOCATION C25
J 0
(2700 525);
DISPLAY 1.021277 (2700 525);
DISPLAY INVISIBLE (2700 525);
FORCEPROP 2 LAST $SEC 1
J 0
(2700 525);
DISPLAY 0.680851 (2700 525);
PAINT MONO (2700 525);
DISPLAY INVISIBLE (2700 525);
FORCEPROP 2 LAST CDS_SEC 1
J 0
(2700 525);
DISPLAY 1.021277 (2700 525);
DISPLAY INVISIBLE (2700 525);
FORCEPROP 1 LAST PATH I127
J 0
(2700 475);
DISPLAY 0.978723 (2700 475);
PAINT WHITE (2700 475);
DISPLAY INVISIBLE (2700 475);
FORCEADD UNIVERSAL_GND..1
(3725 500);
FORCEPROP 3 LASTPIN (3725 550) SIG_NAME GND\g
J 0
(3735 560);
DISPLAY 0.659574 (3735 560);
PAINT MONO (3735 560);
DISPLAY INVISIBLE (3735 560);
FORCEPROP 2 LAST CDS_LIB logical_power
J 0
(3725 500);
PAINT MONO (3725 500);
DISPLAY INVISIBLE (3725 500);
FORCEPROP 1 LAST HDL_POWER GND
J 1
(3750 425);
DISPLAY 0.872340 (3750 425);
PAINT GREEN (3750 425);
DISPLAY INVISIBLE (3750 425);
FORCEPROP 1 LAST PATH I128
J 0
(3800 500);
DISPLAY 0.872340 (3800 500);
PAINT AQUA (3800 500);
DISPLAY INVISIBLE (3800 500);
FORCEADD TAP..1
(2050 2250);
FORCEPROP 3 LASTPIN (2000 2250) SIG_NAME M_D_CPU0_SB_DQS_DP<0>
J 0
(2010 2260);
DISPLAY 0.659574 (2010 2260);
PAINT MONO (2010 2260);
DISPLAY INVISIBLE (2010 2260);
FORCEPROP 1 LASTPIN (2000 2250) BN 0
J 0
(1988 2258);
DISPLAY 0.680851 (1988 2258);
PAINT GREEN (1988 2258);
FORCEPROP 2 LAST CDS_LIB standard
J 0
(2050 2250);
PAINT MONO (2050 2250);
DISPLAY INVISIBLE (2050 2250);
FORCEPROP 1 LAST BODY_TYPE PLUMBING
J 0
(2050 2300);
DISPLAY 0.872340 (2050 2300);
PAINT GREEN (2050 2300);
DISPLAY INVISIBLE (2050 2300);
FORCEPROP 1 LAST HDL_TAP TRUE
J 0
(2375 2125);
DISPLAY 0.872340 (2375 2125);
DISPLAY INVISIBLE (2375 2125);
FORCEPROP 1 LAST PATH I129
J 0
(2048 2250);
DISPLAY 0.872340 (2048 2250);
PAINT GREEN (2048 2250);
DISPLAY INVISIBLE (2048 2250);
FORCEADD OFFPAGE..3
R 2
(-3275 2375);
FORCEPROP 2 LAST $XR1 88 
J 0
(-3614 2375);
DISPLAY 0.638298 (-3614 2375);
PAINT MONO (-3614 2375);
FORCEPROP 2 LAST $XR0 23 
J 0
(-3524 2375);
DISPLAY 0.638298 (-3524 2375);
PAINT MONO (-3524 2375);
FORCEPROP 2 LAST CDS_LIB standard
J 0
(-3275 2375);
PAINT MONO (-3275 2375);
DISPLAY INVISIBLE (-3275 2375);
FORCEPROP 1 LAST OFFPAGE TRUE
J 2
(-3600 2250);
DISPLAY 0.872340 (-3600 2250);
DISPLAY INVISIBLE (-3600 2250);
FORCEPROP 1 LAST COMMENT_BODY TRUE
J 2
(-3225 2275);
DISPLAY 0.872340 (-3225 2275);
PAINT GREEN (-3225 2275);
DISPLAY INVISIBLE (-3225 2275);
FORCEPROP 2 LAST PATH I13
J 0
(-3225 2450);
DISPLAY 1.021277 (-3225 2450);
DISPLAY INVISIBLE (-3225 2450);
FORCEADD TAP..1
(2050 2350);
FORCEPROP 3 LASTPIN (2000 2350) SIG_NAME M_D_CPU0_SB_DQS_DP<1>
J 0
(2010 2360);
DISPLAY 0.659574 (2010 2360);
PAINT MONO (2010 2360);
DISPLAY INVISIBLE (2010 2360);
FORCEPROP 1 LASTPIN (2000 2350) BN 1
J 0
(1988 2358);
DISPLAY 0.680851 (1988 2358);
PAINT GREEN (1988 2358);
FORCEPROP 2 LAST CDS_LIB standard
J 0
(2050 2350);
DISPLAY INVISIBLE (2050 2350);
FORCEPROP 1 LAST BODY_TYPE PLUMBING
J 0
(2050 2400);
DISPLAY 0.872340 (2050 2400);
PAINT GREEN (2050 2400);
DISPLAY INVISIBLE (2050 2400);
FORCEPROP 1 LAST HDL_TAP TRUE
J 0
(2375 2225);
DISPLAY 0.872340 (2375 2225);
DISPLAY INVISIBLE (2375 2225);
FORCEPROP 1 LAST PATH I130
J 0
(2048 2350);
DISPLAY 0.872340 (2048 2350);
PAINT GREEN (2048 2350);
DISPLAY INVISIBLE (2048 2350);
FORCEADD TAP..1
(2050 2450);
FORCEPROP 3 LASTPIN (2000 2450) SIG_NAME M_D_CPU0_SB_DQS_DP<2>
J 0
(2010 2460);
DISPLAY 0.659574 (2010 2460);
PAINT MONO (2010 2460);
DISPLAY INVISIBLE (2010 2460);
FORCEPROP 1 LASTPIN (2000 2450) BN 2
J 0
(1988 2458);
DISPLAY 0.680851 (1988 2458);
PAINT GREEN (1988 2458);
FORCEPROP 2 LAST CDS_LIB standard
J 0
(2050 2450);
DISPLAY INVISIBLE (2050 2450);
FORCEPROP 1 LAST BODY_TYPE PLUMBING
J 0
(2050 2500);
DISPLAY 0.872340 (2050 2500);
PAINT GREEN (2050 2500);
DISPLAY INVISIBLE (2050 2500);
FORCEPROP 1 LAST HDL_TAP TRUE
J 0
(2375 2325);
DISPLAY 0.872340 (2375 2325);
DISPLAY INVISIBLE (2375 2325);
FORCEPROP 1 LAST PATH I131
J 0
(2048 2450);
DISPLAY 0.872340 (2048 2450);
PAINT GREEN (2048 2450);
DISPLAY INVISIBLE (2048 2450);
FORCEADD TAP..1
(2050 2550);
FORCEPROP 3 LASTPIN (2000 2550) SIG_NAME M_D_CPU0_SB_DQS_DP<3>
J 0
(2010 2560);
DISPLAY 0.659574 (2010 2560);
PAINT MONO (2010 2560);
DISPLAY INVISIBLE (2010 2560);
FORCEPROP 1 LASTPIN (2000 2550) BN 3
J 0
(1988 2558);
DISPLAY 0.680851 (1988 2558);
PAINT GREEN (1988 2558);
FORCEPROP 2 LAST CDS_LIB standard
J 0
(2050 2550);
PAINT MONO (2050 2550);
DISPLAY INVISIBLE (2050 2550);
FORCEPROP 1 LAST BODY_TYPE PLUMBING
J 0
(2050 2600);
DISPLAY 0.872340 (2050 2600);
PAINT GREEN (2050 2600);
DISPLAY INVISIBLE (2050 2600);
FORCEPROP 1 LAST HDL_TAP TRUE
J 0
(2375 2425);
DISPLAY 0.872340 (2375 2425);
DISPLAY INVISIBLE (2375 2425);
FORCEPROP 1 LAST PATH I132
J 0
(2048 2550);
DISPLAY 0.872340 (2048 2550);
PAINT GREEN (2048 2550);
DISPLAY INVISIBLE (2048 2550);
FORCEADD TAP..1
(2225 2300);
FORCEPROP 3 LASTPIN (2175 2300) SIG_NAME M_D_CPU0_SB_DQS_DN<1>
J 0
(2185 2310);
DISPLAY 0.659574 (2185 2310);
PAINT MONO (2185 2310);
DISPLAY INVISIBLE (2185 2310);
FORCEPROP 1 LASTPIN (2175 2300) BN 1
J 0
(2163 2308);
DISPLAY 0.680851 (2163 2308);
PAINT GREEN (2163 2308);
FORCEPROP 2 LAST CDS_LIB standard
J 0
(2225 2300);
DISPLAY INVISIBLE (2225 2300);
FORCEPROP 1 LAST BODY_TYPE PLUMBING
J 0
(2225 2350);
DISPLAY 0.872340 (2225 2350);
PAINT GREEN (2225 2350);
DISPLAY INVISIBLE (2225 2350);
FORCEPROP 1 LAST HDL_TAP TRUE
J 0
(2550 2175);
DISPLAY 0.872340 (2550 2175);
DISPLAY INVISIBLE (2550 2175);
FORCEPROP 1 LAST PATH I133
J 0
(2223 2300);
DISPLAY 0.872340 (2223 2300);
PAINT GREEN (2223 2300);
DISPLAY INVISIBLE (2223 2300);
FORCEADD TAP..1
(2225 2200);
FORCEPROP 3 LASTPIN (2175 2200) SIG_NAME M_D_CPU0_SB_DQS_DN<0>
J 0
(2185 2210);
DISPLAY 0.659574 (2185 2210);
PAINT MONO (2185 2210);
DISPLAY INVISIBLE (2185 2210);
FORCEPROP 1 LASTPIN (2175 2200) BN 0
J 0
(2163 2208);
DISPLAY 0.680851 (2163 2208);
PAINT GREEN (2163 2208);
FORCEPROP 2 LAST CDS_LIB standard
J 0
(2225 2200);
PAINT MONO (2225 2200);
DISPLAY INVISIBLE (2225 2200);
FORCEPROP 1 LAST BODY_TYPE PLUMBING
J 0
(2225 2250);
DISPLAY 0.872340 (2225 2250);
PAINT GREEN (2225 2250);
DISPLAY INVISIBLE (2225 2250);
FORCEPROP 1 LAST HDL_TAP TRUE
J 0
(2550 2075);
DISPLAY 0.872340 (2550 2075);
DISPLAY INVISIBLE (2550 2075);
FORCEPROP 1 LAST PATH I134
J 0
(2223 2200);
DISPLAY 0.872340 (2223 2200);
PAINT GREEN (2223 2200);
DISPLAY INVISIBLE (2223 2200);
FORCEADD TAP..1
(2225 2400);
FORCEPROP 3 LASTPIN (2175 2400) SIG_NAME M_D_CPU0_SB_DQS_DN<2>
J 0
(2185 2410);
DISPLAY 0.659574 (2185 2410);
PAINT MONO (2185 2410);
DISPLAY INVISIBLE (2185 2410);
FORCEPROP 1 LASTPIN (2175 2400) BN 2
J 0
(2163 2408);
DISPLAY 0.680851 (2163 2408);
PAINT GREEN (2163 2408);
FORCEPROP 2 LAST CDS_LIB standard
J 0
(2225 2400);
DISPLAY INVISIBLE (2225 2400);
FORCEPROP 1 LAST BODY_TYPE PLUMBING
J 0
(2225 2450);
DISPLAY 0.872340 (2225 2450);
PAINT GREEN (2225 2450);
DISPLAY INVISIBLE (2225 2450);
FORCEPROP 1 LAST HDL_TAP TRUE
J 0
(2550 2275);
DISPLAY 0.872340 (2550 2275);
DISPLAY INVISIBLE (2550 2275);
FORCEPROP 1 LAST PATH I135
J 0
(2223 2400);
DISPLAY 0.872340 (2223 2400);
PAINT GREEN (2223 2400);
DISPLAY INVISIBLE (2223 2400);
FORCEADD TAP..1
(2225 2500);
FORCEPROP 3 LASTPIN (2175 2500) SIG_NAME M_D_CPU0_SB_DQS_DN<3>
J 0
(2185 2510);
DISPLAY 0.659574 (2185 2510);
PAINT MONO (2185 2510);
DISPLAY INVISIBLE (2185 2510);
FORCEPROP 1 LASTPIN (2175 2500) BN 3
J 0
(2163 2508);
DISPLAY 0.680851 (2163 2508);
PAINT GREEN (2163 2508);
FORCEPROP 2 LAST CDS_LIB standard
J 0
(2225 2500);
PAINT MONO (2225 2500);
DISPLAY INVISIBLE (2225 2500);
FORCEPROP 1 LAST BODY_TYPE PLUMBING
J 0
(2225 2550);
DISPLAY 0.872340 (2225 2550);
PAINT GREEN (2225 2550);
DISPLAY INVISIBLE (2225 2550);
FORCEPROP 1 LAST HDL_TAP TRUE
J 0
(2550 2375);
DISPLAY 0.872340 (2550 2375);
DISPLAY INVISIBLE (2550 2375);
FORCEPROP 1 LAST PATH I136
J 0
(2223 2500);
DISPLAY 0.872340 (2223 2500);
PAINT GREEN (2223 2500);
DISPLAY INVISIBLE (2223 2500);
FORCEADD TAP..1
(2050 2650);
FORCEPROP 3 LASTPIN (2000 2650) SIG_NAME M_D_CPU0_SB_DQS_DP<4>
J 0
(2010 2660);
DISPLAY 0.659574 (2010 2660);
PAINT MONO (2010 2660);
DISPLAY INVISIBLE (2010 2660);
FORCEPROP 1 LASTPIN (2000 2650) BN 4
J 0
(1988 2658);
DISPLAY 0.680851 (1988 2658);
PAINT GREEN (1988 2658);
FORCEPROP 2 LAST CDS_LIB standard
J 0
(2050 2650);
PAINT MONO (2050 2650);
DISPLAY INVISIBLE (2050 2650);
FORCEPROP 1 LAST BODY_TYPE PLUMBING
J 0
(2050 2700);
DISPLAY 0.872340 (2050 2700);
PAINT GREEN (2050 2700);
DISPLAY INVISIBLE (2050 2700);
FORCEPROP 1 LAST HDL_TAP TRUE
J 0
(2375 2525);
DISPLAY 0.872340 (2375 2525);
DISPLAY INVISIBLE (2375 2525);
FORCEPROP 1 LAST PATH I137
J 0
(2048 2650);
DISPLAY 0.872340 (2048 2650);
PAINT GREEN (2048 2650);
DISPLAY INVISIBLE (2048 2650);
FORCEADD TAP..1
(2050 2750);
FORCEPROP 3 LASTPIN (2000 2750) SIG_NAME M_D_CPU0_SB_DQS_DP<5>
J 0
(2010 2760);
DISPLAY 0.659574 (2010 2760);
PAINT MONO (2010 2760);
DISPLAY INVISIBLE (2010 2760);
FORCEPROP 1 LASTPIN (2000 2750) BN 5
J 0
(1988 2758);
DISPLAY 0.680851 (1988 2758);
PAINT GREEN (1988 2758);
FORCEPROP 2 LAST CDS_LIB standard
J 0
(2050 2750);
DISPLAY INVISIBLE (2050 2750);
FORCEPROP 1 LAST BODY_TYPE PLUMBING
J 0
(2050 2800);
DISPLAY 0.872340 (2050 2800);
PAINT GREEN (2050 2800);
DISPLAY INVISIBLE (2050 2800);
FORCEPROP 1 LAST HDL_TAP TRUE
J 0
(2375 2625);
DISPLAY 0.872340 (2375 2625);
DISPLAY INVISIBLE (2375 2625);
FORCEPROP 1 LAST PATH I138
J 0
(2048 2750);
DISPLAY 0.872340 (2048 2750);
PAINT GREEN (2048 2750);
DISPLAY INVISIBLE (2048 2750);
FORCEADD TAP..1
(2050 2850);
FORCEPROP 3 LASTPIN (2000 2850) SIG_NAME M_D_CPU0_SB_DQS_DP<6>
J 0
(2010 2860);
DISPLAY 0.659574 (2010 2860);
PAINT MONO (2010 2860);
DISPLAY INVISIBLE (2010 2860);
FORCEPROP 1 LASTPIN (2000 2850) BN 6
J 0
(1988 2858);
DISPLAY 0.680851 (1988 2858);
PAINT GREEN (1988 2858);
FORCEPROP 2 LAST CDS_LIB standard
J 0
(2050 2850);
DISPLAY INVISIBLE (2050 2850);
FORCEPROP 1 LAST BODY_TYPE PLUMBING
J 0
(2050 2900);
DISPLAY 0.872340 (2050 2900);
PAINT GREEN (2050 2900);
DISPLAY INVISIBLE (2050 2900);
FORCEPROP 1 LAST HDL_TAP TRUE
J 0
(2375 2725);
DISPLAY 0.872340 (2375 2725);
DISPLAY INVISIBLE (2375 2725);
FORCEPROP 1 LAST PATH I139
J 0
(2048 2850);
DISPLAY 0.872340 (2048 2850);
PAINT GREEN (2048 2850);
DISPLAY INVISIBLE (2048 2850);
FORCEADD OFFPAGE..3
R 2
(-3275 2825);
FORCEPROP 2 LAST $XR1 88 
J 0
(-3614 2825);
DISPLAY 0.638298 (-3614 2825);
PAINT MONO (-3614 2825);
FORCEPROP 2 LAST $XR0 23 
J 0
(-3524 2825);
DISPLAY 0.638298 (-3524 2825);
PAINT MONO (-3524 2825);
FORCEPROP 2 LAST CDS_LIB standard
J 0
(-3275 2825);
PAINT MONO (-3275 2825);
DISPLAY INVISIBLE (-3275 2825);
FORCEPROP 1 LAST OFFPAGE TRUE
J 2
(-3600 2700);
DISPLAY 0.872340 (-3600 2700);
DISPLAY INVISIBLE (-3600 2700);
FORCEPROP 1 LAST COMMENT_BODY TRUE
J 2
(-3225 2725);
DISPLAY 0.872340 (-3225 2725);
PAINT GREEN (-3225 2725);
DISPLAY INVISIBLE (-3225 2725);
FORCEPROP 2 LAST PATH I14
J 0
(-3225 2900);
DISPLAY 1.021277 (-3225 2900);
DISPLAY INVISIBLE (-3225 2900);
FORCEADD TAP..1
(2050 2950);
FORCEPROP 3 LASTPIN (2000 2950) SIG_NAME M_D_CPU0_SB_DQS_DP<7>
J 0
(2010 2960);
DISPLAY 0.659574 (2010 2960);
PAINT MONO (2010 2960);
DISPLAY INVISIBLE (2010 2960);
FORCEPROP 1 LASTPIN (2000 2950) BN 7
J 0
(1988 2958);
DISPLAY 0.680851 (1988 2958);
PAINT GREEN (1988 2958);
FORCEPROP 2 LAST CDS_LIB standard
J 0
(2050 2950);
DISPLAY INVISIBLE (2050 2950);
FORCEPROP 1 LAST BODY_TYPE PLUMBING
J 0
(2050 3000);
DISPLAY 0.872340 (2050 3000);
PAINT GREEN (2050 3000);
DISPLAY INVISIBLE (2050 3000);
FORCEPROP 1 LAST HDL_TAP TRUE
J 0
(2375 2825);
DISPLAY 0.872340 (2375 2825);
DISPLAY INVISIBLE (2375 2825);
FORCEPROP 1 LAST PATH I140
J 0
(2048 2950);
DISPLAY 0.872340 (2048 2950);
PAINT GREEN (2048 2950);
DISPLAY INVISIBLE (2048 2950);
FORCEADD TAP..1
(2050 3050);
FORCEPROP 3 LASTPIN (2000 3050) SIG_NAME M_D_CPU0_SB_DQS_DP<8>
J 0
(2010 3060);
DISPLAY 0.659574 (2010 3060);
PAINT MONO (2010 3060);
DISPLAY INVISIBLE (2010 3060);
FORCEPROP 1 LASTPIN (2000 3050) BN 8
J 0
(1988 3058);
DISPLAY 0.680851 (1988 3058);
PAINT GREEN (1988 3058);
FORCEPROP 2 LAST CDS_LIB standard
J 0
(2050 3050);
DISPLAY INVISIBLE (2050 3050);
FORCEPROP 1 LAST BODY_TYPE PLUMBING
J 0
(2050 3100);
DISPLAY 0.872340 (2050 3100);
PAINT GREEN (2050 3100);
DISPLAY INVISIBLE (2050 3100);
FORCEPROP 1 LAST HDL_TAP TRUE
J 0
(2375 2925);
DISPLAY 0.872340 (2375 2925);
DISPLAY INVISIBLE (2375 2925);
FORCEPROP 1 LAST PATH I141
J 0
(2048 3050);
DISPLAY 0.872340 (2048 3050);
PAINT GREEN (2048 3050);
DISPLAY INVISIBLE (2048 3050);
FORCEADD TAP..1
(2225 2600);
FORCEPROP 3 LASTPIN (2175 2600) SIG_NAME M_D_CPU0_SB_DQS_DN<4>
J 0
(2185 2610);
DISPLAY 0.659574 (2185 2610);
PAINT MONO (2185 2610);
DISPLAY INVISIBLE (2185 2610);
FORCEPROP 1 LASTPIN (2175 2600) BN 4
J 0
(2163 2608);
DISPLAY 0.680851 (2163 2608);
PAINT GREEN (2163 2608);
FORCEPROP 2 LAST CDS_LIB standard
J 0
(2225 2600);
PAINT MONO (2225 2600);
DISPLAY INVISIBLE (2225 2600);
FORCEPROP 1 LAST BODY_TYPE PLUMBING
J 0
(2225 2650);
DISPLAY 0.872340 (2225 2650);
PAINT GREEN (2225 2650);
DISPLAY INVISIBLE (2225 2650);
FORCEPROP 1 LAST HDL_TAP TRUE
J 0
(2550 2475);
DISPLAY 0.872340 (2550 2475);
DISPLAY INVISIBLE (2550 2475);
FORCEPROP 1 LAST PATH I142
J 0
(2223 2600);
DISPLAY 0.872340 (2223 2600);
PAINT GREEN (2223 2600);
DISPLAY INVISIBLE (2223 2600);
FORCEADD TAP..1
(2225 2800);
FORCEPROP 3 LASTPIN (2175 2800) SIG_NAME M_D_CPU0_SB_DQS_DN<6>
J 0
(2185 2810);
DISPLAY 0.659574 (2185 2810);
PAINT MONO (2185 2810);
DISPLAY INVISIBLE (2185 2810);
FORCEPROP 1 LASTPIN (2175 2800) BN 6
J 0
(2163 2808);
DISPLAY 0.680851 (2163 2808);
PAINT GREEN (2163 2808);
FORCEPROP 2 LAST CDS_LIB standard
J 0
(2225 2800);
DISPLAY INVISIBLE (2225 2800);
FORCEPROP 1 LAST BODY_TYPE PLUMBING
J 0
(2225 2850);
DISPLAY 0.872340 (2225 2850);
PAINT GREEN (2225 2850);
DISPLAY INVISIBLE (2225 2850);
FORCEPROP 1 LAST HDL_TAP TRUE
J 0
(2550 2675);
DISPLAY 0.872340 (2550 2675);
DISPLAY INVISIBLE (2550 2675);
FORCEPROP 1 LAST PATH I143
J 0
(2223 2800);
DISPLAY 0.872340 (2223 2800);
PAINT GREEN (2223 2800);
DISPLAY INVISIBLE (2223 2800);
FORCEADD TAP..1
(2225 2700);
FORCEPROP 3 LASTPIN (2175 2700) SIG_NAME M_D_CPU0_SB_DQS_DN<5>
J 0
(2185 2710);
DISPLAY 0.659574 (2185 2710);
PAINT MONO (2185 2710);
DISPLAY INVISIBLE (2185 2710);
FORCEPROP 1 LASTPIN (2175 2700) BN 5
J 0
(2163 2708);
DISPLAY 0.680851 (2163 2708);
PAINT GREEN (2163 2708);
FORCEPROP 2 LAST CDS_LIB standard
J 0
(2225 2700);
DISPLAY INVISIBLE (2225 2700);
FORCEPROP 1 LAST BODY_TYPE PLUMBING
J 0
(2225 2750);
DISPLAY 0.872340 (2225 2750);
PAINT GREEN (2225 2750);
DISPLAY INVISIBLE (2225 2750);
FORCEPROP 1 LAST HDL_TAP TRUE
J 0
(2550 2575);
DISPLAY 0.872340 (2550 2575);
DISPLAY INVISIBLE (2550 2575);
FORCEPROP 1 LAST PATH I144
J 0
(2223 2700);
DISPLAY 0.872340 (2223 2700);
PAINT GREEN (2223 2700);
DISPLAY INVISIBLE (2223 2700);
FORCEADD TAP..1
(2225 2900);
FORCEPROP 3 LASTPIN (2175 2900) SIG_NAME M_D_CPU0_SB_DQS_DN<7>
J 0
(2185 2910);
DISPLAY 0.659574 (2185 2910);
PAINT MONO (2185 2910);
DISPLAY INVISIBLE (2185 2910);
FORCEPROP 1 LASTPIN (2175 2900) BN 7
J 0
(2163 2908);
DISPLAY 0.680851 (2163 2908);
PAINT GREEN (2163 2908);
FORCEPROP 2 LAST CDS_LIB standard
J 0
(2225 2900);
DISPLAY INVISIBLE (2225 2900);
FORCEPROP 1 LAST BODY_TYPE PLUMBING
J 0
(2225 2950);
DISPLAY 0.872340 (2225 2950);
PAINT GREEN (2225 2950);
DISPLAY INVISIBLE (2225 2950);
FORCEPROP 1 LAST HDL_TAP TRUE
J 0
(2550 2775);
DISPLAY 0.872340 (2550 2775);
DISPLAY INVISIBLE (2550 2775);
FORCEPROP 1 LAST PATH I145
J 0
(2223 2900);
DISPLAY 0.872340 (2223 2900);
PAINT GREEN (2223 2900);
DISPLAY INVISIBLE (2223 2900);
FORCEADD TAP..1
(2225 3000);
FORCEPROP 3 LASTPIN (2175 3000) SIG_NAME M_D_CPU0_SB_DQS_DN<8>
J 0
(2185 3010);
DISPLAY 0.659574 (2185 3010);
PAINT MONO (2185 3010);
DISPLAY INVISIBLE (2185 3010);
FORCEPROP 1 LASTPIN (2175 3000) BN 8
J 0
(2163 3008);
DISPLAY 0.680851 (2163 3008);
PAINT GREEN (2163 3008);
FORCEPROP 2 LAST CDS_LIB standard
J 0
(2225 3000);
DISPLAY INVISIBLE (2225 3000);
FORCEPROP 1 LAST BODY_TYPE PLUMBING
J 0
(2225 3050);
DISPLAY 0.872340 (2225 3050);
PAINT GREEN (2225 3050);
DISPLAY INVISIBLE (2225 3050);
FORCEPROP 1 LAST HDL_TAP TRUE
J 0
(2550 2875);
DISPLAY 0.872340 (2550 2875);
DISPLAY INVISIBLE (2550 2875);
FORCEPROP 1 LAST PATH I146
J 0
(2223 3000);
DISPLAY 0.872340 (2223 3000);
PAINT GREEN (2223 3000);
DISPLAY INVISIBLE (2223 3000);
FORCEADD TAP..1
(2050 3150);
FORCEPROP 3 LASTPIN (2000 3150) SIG_NAME M_D_CPU0_SB_DQS_DP<9>
J 0
(2010 3160);
DISPLAY 0.659574 (2010 3160);
PAINT MONO (2010 3160);
DISPLAY INVISIBLE (2010 3160);
FORCEPROP 1 LASTPIN (2000 3150) BN 9
J 0
(1988 3158);
DISPLAY 0.680851 (1988 3158);
PAINT GREEN (1988 3158);
FORCEPROP 2 LAST CDS_LIB standard
J 0
(2050 3150);
DISPLAY INVISIBLE (2050 3150);
FORCEPROP 1 LAST BODY_TYPE PLUMBING
J 0
(2050 3200);
DISPLAY 0.872340 (2050 3200);
PAINT GREEN (2050 3200);
DISPLAY INVISIBLE (2050 3200);
FORCEPROP 1 LAST HDL_TAP TRUE
J 0
(2375 3025);
DISPLAY 0.872340 (2375 3025);
DISPLAY INVISIBLE (2375 3025);
FORCEPROP 1 LAST PATH I147
J 0
(2048 3150);
DISPLAY 0.872340 (2048 3150);
PAINT GREEN (2048 3150);
DISPLAY INVISIBLE (2048 3150);
FORCEADD TAP..1
(2050 3300);
FORCEPROP 3 LASTPIN (2000 3300) SIG_NAME M_D_CPU0_SA_DQS_DP<0>
J 0
(2010 3310);
DISPLAY 0.659574 (2010 3310);
PAINT MONO (2010 3310);
DISPLAY INVISIBLE (2010 3310);
FORCEPROP 1 LASTPIN (2000 3300) BN 0
J 0
(1988 3308);
DISPLAY 0.680851 (1988 3308);
PAINT GREEN (1988 3308);
FORCEPROP 2 LAST CDS_LIB standard
J 0
(2050 3300);
PAINT MONO (2050 3300);
DISPLAY INVISIBLE (2050 3300);
FORCEPROP 1 LAST BODY_TYPE PLUMBING
J 0
(2050 3350);
DISPLAY 0.872340 (2050 3350);
PAINT GREEN (2050 3350);
DISPLAY INVISIBLE (2050 3350);
FORCEPROP 1 LAST HDL_TAP TRUE
J 0
(2375 3175);
DISPLAY 0.872340 (2375 3175);
DISPLAY INVISIBLE (2375 3175);
FORCEPROP 1 LAST PATH I148
J 0
(2048 3300);
DISPLAY 0.872340 (2048 3300);
PAINT GREEN (2048 3300);
DISPLAY INVISIBLE (2048 3300);
FORCEADD TAP..1
(2050 3400);
FORCEPROP 3 LASTPIN (2000 3400) SIG_NAME M_D_CPU0_SA_DQS_DP<1>
J 0
(2010 3410);
DISPLAY 0.659574 (2010 3410);
PAINT MONO (2010 3410);
DISPLAY INVISIBLE (2010 3410);
FORCEPROP 1 LASTPIN (2000 3400) BN 1
J 0
(1988 3408);
DISPLAY 0.680851 (1988 3408);
PAINT GREEN (1988 3408);
FORCEPROP 2 LAST CDS_LIB standard
J 0
(2050 3400);
DISPLAY INVISIBLE (2050 3400);
FORCEPROP 1 LAST BODY_TYPE PLUMBING
J 0
(2050 3450);
DISPLAY 0.872340 (2050 3450);
PAINT GREEN (2050 3450);
DISPLAY INVISIBLE (2050 3450);
FORCEPROP 1 LAST HDL_TAP TRUE
J 0
(2375 3275);
DISPLAY 0.872340 (2375 3275);
DISPLAY INVISIBLE (2375 3275);
FORCEPROP 1 LAST PATH I149
J 0
(2048 3400);
DISPLAY 0.872340 (2048 3400);
PAINT GREEN (2048 3400);
DISPLAY INVISIBLE (2048 3400);
FORCEADD OFFPAGE..1
(-3275 2900);
FORCEPROP 2 LAST $XR0 23 
J 0
(-3496 2900);
DISPLAY 0.638298 (-3496 2900);
PAINT MONO (-3496 2900);
FORCEPROP 2 LAST CDS_LIB standard
J 0
(-3275 2900);
PAINT MONO (-3275 2900);
DISPLAY INVISIBLE (-3275 2900);
FORCEPROP 1 LAST OFFPAGE TRUE
J 0
(-2950 2775);
DISPLAY 0.872340 (-2950 2775);
DISPLAY INVISIBLE (-2950 2775);
FORCEPROP 1 LAST COMMENT_BODY TRUE
J 0
(-3150 2800);
DISPLAY 0.872340 (-3150 2800);
PAINT GREEN (-3150 2800);
DISPLAY INVISIBLE (-3150 2800);
FORCEPROP 2 LAST PATH I15
J 0
(-3225 2975);
DISPLAY 1.021277 (-3225 2975);
DISPLAY INVISIBLE (-3225 2975);
FORCEADD TAP..1
(2050 3500);
FORCEPROP 3 LASTPIN (2000 3500) SIG_NAME M_D_CPU0_SA_DQS_DP<2>
J 0
(2010 3510);
DISPLAY 0.659574 (2010 3510);
PAINT MONO (2010 3510);
DISPLAY INVISIBLE (2010 3510);
FORCEPROP 1 LASTPIN (2000 3500) BN 2
J 0
(1988 3508);
DISPLAY 0.680851 (1988 3508);
PAINT GREEN (1988 3508);
FORCEPROP 2 LAST CDS_LIB standard
J 0
(2050 3500);
DISPLAY INVISIBLE (2050 3500);
FORCEPROP 1 LAST BODY_TYPE PLUMBING
J 0
(2050 3550);
DISPLAY 0.872340 (2050 3550);
PAINT GREEN (2050 3550);
DISPLAY INVISIBLE (2050 3550);
FORCEPROP 1 LAST HDL_TAP TRUE
J 0
(2375 3375);
DISPLAY 0.872340 (2375 3375);
DISPLAY INVISIBLE (2375 3375);
FORCEPROP 1 LAST PATH I150
J 0
(2048 3500);
DISPLAY 0.872340 (2048 3500);
PAINT GREEN (2048 3500);
DISPLAY INVISIBLE (2048 3500);
FORCEADD TAP..1
(2225 3100);
FORCEPROP 3 LASTPIN (2175 3100) SIG_NAME M_D_CPU0_SB_DQS_DN<9>
J 0
(2185 3110);
DISPLAY 0.659574 (2185 3110);
PAINT MONO (2185 3110);
DISPLAY INVISIBLE (2185 3110);
FORCEPROP 1 LASTPIN (2175 3100) BN 9
J 0
(2163 3108);
DISPLAY 0.680851 (2163 3108);
PAINT GREEN (2163 3108);
FORCEPROP 2 LAST CDS_LIB standard
J 0
(2225 3100);
DISPLAY INVISIBLE (2225 3100);
FORCEPROP 1 LAST BODY_TYPE PLUMBING
J 0
(2225 3150);
DISPLAY 0.872340 (2225 3150);
PAINT GREEN (2225 3150);
DISPLAY INVISIBLE (2225 3150);
FORCEPROP 1 LAST HDL_TAP TRUE
J 0
(2550 2975);
DISPLAY 0.872340 (2550 2975);
DISPLAY INVISIBLE (2550 2975);
FORCEPROP 1 LAST PATH I151
J 0
(2223 3100);
DISPLAY 0.872340 (2223 3100);
PAINT GREEN (2223 3100);
DISPLAY INVISIBLE (2223 3100);
FORCEADD TAP..1
(2225 3250);
FORCEPROP 3 LASTPIN (2175 3250) SIG_NAME M_D_CPU0_SA_DQS_DN<0>
J 0
(2185 3260);
DISPLAY 0.659574 (2185 3260);
PAINT MONO (2185 3260);
DISPLAY INVISIBLE (2185 3260);
FORCEPROP 1 LASTPIN (2175 3250) BN 0
J 0
(2163 3258);
DISPLAY 0.680851 (2163 3258);
PAINT GREEN (2163 3258);
FORCEPROP 2 LAST CDS_LIB standard
J 0
(2225 3250);
PAINT MONO (2225 3250);
DISPLAY INVISIBLE (2225 3250);
FORCEPROP 1 LAST BODY_TYPE PLUMBING
J 0
(2225 3300);
DISPLAY 0.872340 (2225 3300);
PAINT GREEN (2225 3300);
DISPLAY INVISIBLE (2225 3300);
FORCEPROP 1 LAST HDL_TAP TRUE
J 0
(2550 3125);
DISPLAY 0.872340 (2550 3125);
DISPLAY INVISIBLE (2550 3125);
FORCEPROP 1 LAST PATH I152
J 0
(2223 3250);
DISPLAY 0.872340 (2223 3250);
PAINT GREEN (2223 3250);
DISPLAY INVISIBLE (2223 3250);
FORCEADD TAP..1
(2225 3450);
FORCEPROP 3 LASTPIN (2175 3450) SIG_NAME M_D_CPU0_SA_DQS_DN<2>
J 0
(2185 3460);
DISPLAY 0.659574 (2185 3460);
PAINT MONO (2185 3460);
DISPLAY INVISIBLE (2185 3460);
FORCEPROP 1 LASTPIN (2175 3450) BN 2
J 0
(2163 3458);
DISPLAY 0.680851 (2163 3458);
PAINT GREEN (2163 3458);
FORCEPROP 2 LAST CDS_LIB standard
J 0
(2225 3450);
DISPLAY INVISIBLE (2225 3450);
FORCEPROP 1 LAST BODY_TYPE PLUMBING
J 0
(2225 3500);
DISPLAY 0.872340 (2225 3500);
PAINT GREEN (2225 3500);
DISPLAY INVISIBLE (2225 3500);
FORCEPROP 1 LAST HDL_TAP TRUE
J 0
(2550 3325);
DISPLAY 0.872340 (2550 3325);
DISPLAY INVISIBLE (2550 3325);
FORCEPROP 1 LAST PATH I153
J 0
(2223 3450);
DISPLAY 0.872340 (2223 3450);
PAINT GREEN (2223 3450);
DISPLAY INVISIBLE (2223 3450);
FORCEADD TAP..1
(2225 3350);
FORCEPROP 3 LASTPIN (2175 3350) SIG_NAME M_D_CPU0_SA_DQS_DN<1>
J 0
(2185 3360);
DISPLAY 0.659574 (2185 3360);
PAINT MONO (2185 3360);
DISPLAY INVISIBLE (2185 3360);
FORCEPROP 1 LASTPIN (2175 3350) BN 1
J 0
(2163 3358);
DISPLAY 0.680851 (2163 3358);
PAINT GREEN (2163 3358);
FORCEPROP 2 LAST CDS_LIB standard
J 0
(2225 3350);
DISPLAY INVISIBLE (2225 3350);
FORCEPROP 1 LAST BODY_TYPE PLUMBING
J 0
(2225 3400);
DISPLAY 0.872340 (2225 3400);
PAINT GREEN (2225 3400);
DISPLAY INVISIBLE (2225 3400);
FORCEPROP 1 LAST HDL_TAP TRUE
J 0
(2550 3225);
DISPLAY 0.872340 (2550 3225);
DISPLAY INVISIBLE (2550 3225);
FORCEPROP 1 LAST PATH I154
J 0
(2223 3350);
DISPLAY 0.872340 (2223 3350);
PAINT GREEN (2223 3350);
DISPLAY INVISIBLE (2223 3350);
FORCEADD TAP..1
(2225 3550);
FORCEPROP 3 LASTPIN (2175 3550) SIG_NAME M_D_CPU0_SA_DQS_DN<3>
J 0
(2185 3560);
DISPLAY 0.659574 (2185 3560);
PAINT MONO (2185 3560);
DISPLAY INVISIBLE (2185 3560);
FORCEPROP 1 LASTPIN (2175 3550) BN 3
J 0
(2163 3558);
DISPLAY 0.680851 (2163 3558);
PAINT GREEN (2163 3558);
FORCEPROP 2 LAST CDS_LIB standard
J 0
(2225 3550);
PAINT MONO (2225 3550);
DISPLAY INVISIBLE (2225 3550);
FORCEPROP 1 LAST BODY_TYPE PLUMBING
J 0
(2225 3600);
DISPLAY 0.872340 (2225 3600);
PAINT GREEN (2225 3600);
DISPLAY INVISIBLE (2225 3600);
FORCEPROP 1 LAST HDL_TAP TRUE
J 0
(2550 3425);
DISPLAY 0.872340 (2550 3425);
DISPLAY INVISIBLE (2550 3425);
FORCEPROP 1 LAST PATH I155
J 0
(2223 3550);
DISPLAY 0.872340 (2223 3550);
PAINT GREEN (2223 3550);
DISPLAY INVISIBLE (2223 3550);
FORCEADD TAP..1
(2050 3600);
FORCEPROP 3 LASTPIN (2000 3600) SIG_NAME M_D_CPU0_SA_DQS_DP<3>
J 0
(2010 3610);
DISPLAY 0.659574 (2010 3610);
PAINT MONO (2010 3610);
DISPLAY INVISIBLE (2010 3610);
FORCEPROP 1 LASTPIN (2000 3600) BN 3
J 0
(1988 3608);
DISPLAY 0.680851 (1988 3608);
PAINT GREEN (1988 3608);
FORCEPROP 2 LAST CDS_LIB standard
J 0
(2050 3600);
PAINT MONO (2050 3600);
DISPLAY INVISIBLE (2050 3600);
FORCEPROP 1 LAST BODY_TYPE PLUMBING
J 0
(2050 3650);
DISPLAY 0.872340 (2050 3650);
PAINT GREEN (2050 3650);
DISPLAY INVISIBLE (2050 3650);
FORCEPROP 1 LAST HDL_TAP TRUE
J 0
(2375 3475);
DISPLAY 0.872340 (2375 3475);
DISPLAY INVISIBLE (2375 3475);
FORCEPROP 1 LAST PATH I156
J 0
(2048 3600);
DISPLAY 0.872340 (2048 3600);
PAINT GREEN (2048 3600);
DISPLAY INVISIBLE (2048 3600);
FORCEADD TAP..1
(2050 3700);
FORCEPROP 3 LASTPIN (2000 3700) SIG_NAME M_D_CPU0_SA_DQS_DP<4>
J 0
(2010 3710);
DISPLAY 0.659574 (2010 3710);
PAINT MONO (2010 3710);
DISPLAY INVISIBLE (2010 3710);
FORCEPROP 1 LASTPIN (2000 3700) BN 4
J 0
(1988 3708);
DISPLAY 0.680851 (1988 3708);
PAINT GREEN (1988 3708);
FORCEPROP 2 LAST CDS_LIB standard
J 0
(2050 3700);
PAINT MONO (2050 3700);
DISPLAY INVISIBLE (2050 3700);
FORCEPROP 1 LAST BODY_TYPE PLUMBING
J 0
(2050 3750);
DISPLAY 0.872340 (2050 3750);
PAINT GREEN (2050 3750);
DISPLAY INVISIBLE (2050 3750);
FORCEPROP 1 LAST HDL_TAP TRUE
J 0
(2375 3575);
DISPLAY 0.872340 (2375 3575);
DISPLAY INVISIBLE (2375 3575);
FORCEPROP 1 LAST PATH I157
J 0
(2048 3700);
DISPLAY 0.872340 (2048 3700);
PAINT GREEN (2048 3700);
DISPLAY INVISIBLE (2048 3700);
FORCEADD TAP..1
(2050 3800);
FORCEPROP 3 LASTPIN (2000 3800) SIG_NAME M_D_CPU0_SA_DQS_DP<5>
J 0
(2010 3810);
DISPLAY 0.659574 (2010 3810);
PAINT MONO (2010 3810);
DISPLAY INVISIBLE (2010 3810);
FORCEPROP 1 LASTPIN (2000 3800) BN 5
J 0
(1988 3808);
DISPLAY 0.680851 (1988 3808);
PAINT GREEN (1988 3808);
FORCEPROP 2 LAST CDS_LIB standard
J 0
(2050 3800);
DISPLAY INVISIBLE (2050 3800);
FORCEPROP 1 LAST BODY_TYPE PLUMBING
J 0
(2050 3850);
DISPLAY 0.872340 (2050 3850);
PAINT GREEN (2050 3850);
DISPLAY INVISIBLE (2050 3850);
FORCEPROP 1 LAST HDL_TAP TRUE
J 0
(2375 3675);
DISPLAY 0.872340 (2375 3675);
DISPLAY INVISIBLE (2375 3675);
FORCEPROP 1 LAST PATH I158
J 0
(2048 3800);
DISPLAY 0.872340 (2048 3800);
PAINT GREEN (2048 3800);
DISPLAY INVISIBLE (2048 3800);
FORCEADD TAP..1
(2050 3900);
FORCEPROP 3 LASTPIN (2000 3900) SIG_NAME M_D_CPU0_SA_DQS_DP<6>
J 0
(2010 3910);
DISPLAY 0.659574 (2010 3910);
PAINT MONO (2010 3910);
DISPLAY INVISIBLE (2010 3910);
FORCEPROP 1 LASTPIN (2000 3900) BN 6
J 0
(1988 3908);
DISPLAY 0.680851 (1988 3908);
PAINT GREEN (1988 3908);
FORCEPROP 2 LAST CDS_LIB standard
J 0
(2050 3900);
DISPLAY INVISIBLE (2050 3900);
FORCEPROP 1 LAST BODY_TYPE PLUMBING
J 0
(2050 3950);
DISPLAY 0.872340 (2050 3950);
PAINT GREEN (2050 3950);
DISPLAY INVISIBLE (2050 3950);
FORCEPROP 1 LAST HDL_TAP TRUE
J 0
(2375 3775);
DISPLAY 0.872340 (2375 3775);
DISPLAY INVISIBLE (2375 3775);
FORCEPROP 1 LAST PATH I159
J 0
(2048 3900);
DISPLAY 0.872340 (2048 3900);
PAINT GREEN (2048 3900);
DISPLAY INVISIBLE (2048 3900);
FORCEADD OFFPAGE..1
(-3275 2950);
FORCEPROP 2 LAST $XR0 23 
J 0
(-3496 2950);
DISPLAY 0.638298 (-3496 2950);
PAINT MONO (-3496 2950);
FORCEPROP 2 LAST CDS_LIB standard
J 0
(-3275 2950);
PAINT MONO (-3275 2950);
DISPLAY INVISIBLE (-3275 2950);
FORCEPROP 1 LAST OFFPAGE TRUE
J 0
(-2950 2825);
DISPLAY 0.872340 (-2950 2825);
DISPLAY INVISIBLE (-2950 2825);
FORCEPROP 1 LAST COMMENT_BODY TRUE
J 0
(-3150 2850);
DISPLAY 0.872340 (-3150 2850);
PAINT GREEN (-3150 2850);
DISPLAY INVISIBLE (-3150 2850);
FORCEPROP 2 LAST PATH I16
J 0
(-3225 3025);
DISPLAY 1.021277 (-3225 3025);
DISPLAY INVISIBLE (-3225 3025);
FORCEADD TAP..1
(2050 4000);
FORCEPROP 3 LASTPIN (2000 4000) SIG_NAME M_D_CPU0_SA_DQS_DP<7>
J 0
(2010 4010);
DISPLAY 0.659574 (2010 4010);
PAINT MONO (2010 4010);
DISPLAY INVISIBLE (2010 4010);
FORCEPROP 1 LASTPIN (2000 4000) BN 7
J 0
(1988 4008);
DISPLAY 0.680851 (1988 4008);
PAINT GREEN (1988 4008);
FORCEPROP 2 LAST CDS_LIB standard
J 0
(2050 4000);
DISPLAY INVISIBLE (2050 4000);
FORCEPROP 1 LAST BODY_TYPE PLUMBING
J 0
(2050 4050);
DISPLAY 0.872340 (2050 4050);
PAINT GREEN (2050 4050);
DISPLAY INVISIBLE (2050 4050);
FORCEPROP 1 LAST HDL_TAP TRUE
J 0
(2375 3875);
DISPLAY 0.872340 (2375 3875);
DISPLAY INVISIBLE (2375 3875);
FORCEPROP 1 LAST PATH I160
J 0
(2048 4000);
DISPLAY 0.872340 (2048 4000);
PAINT GREEN (2048 4000);
DISPLAY INVISIBLE (2048 4000);
FORCEADD TAP..1
(2225 3650);
FORCEPROP 3 LASTPIN (2175 3650) SIG_NAME M_D_CPU0_SA_DQS_DN<4>
J 0
(2185 3660);
DISPLAY 0.659574 (2185 3660);
PAINT MONO (2185 3660);
DISPLAY INVISIBLE (2185 3660);
FORCEPROP 1 LASTPIN (2175 3650) BN 4
J 0
(2163 3658);
DISPLAY 0.680851 (2163 3658);
PAINT GREEN (2163 3658);
FORCEPROP 2 LAST CDS_LIB standard
J 0
(2225 3650);
PAINT MONO (2225 3650);
DISPLAY INVISIBLE (2225 3650);
FORCEPROP 1 LAST BODY_TYPE PLUMBING
J 0
(2225 3700);
DISPLAY 0.872340 (2225 3700);
PAINT GREEN (2225 3700);
DISPLAY INVISIBLE (2225 3700);
FORCEPROP 1 LAST HDL_TAP TRUE
J 0
(2550 3525);
DISPLAY 0.872340 (2550 3525);
DISPLAY INVISIBLE (2550 3525);
FORCEPROP 1 LAST PATH I161
J 0
(2223 3650);
DISPLAY 0.872340 (2223 3650);
PAINT GREEN (2223 3650);
DISPLAY INVISIBLE (2223 3650);
FORCEADD TAP..1
(2225 3750);
FORCEPROP 3 LASTPIN (2175 3750) SIG_NAME M_D_CPU0_SA_DQS_DN<5>
J 0
(2185 3760);
DISPLAY 0.659574 (2185 3760);
PAINT MONO (2185 3760);
DISPLAY INVISIBLE (2185 3760);
FORCEPROP 1 LASTPIN (2175 3750) BN 5
J 0
(2163 3758);
DISPLAY 0.680851 (2163 3758);
PAINT GREEN (2163 3758);
FORCEPROP 2 LAST CDS_LIB standard
J 0
(2225 3750);
DISPLAY INVISIBLE (2225 3750);
FORCEPROP 1 LAST BODY_TYPE PLUMBING
J 0
(2225 3800);
DISPLAY 0.872340 (2225 3800);
PAINT GREEN (2225 3800);
DISPLAY INVISIBLE (2225 3800);
FORCEPROP 1 LAST HDL_TAP TRUE
J 0
(2550 3625);
DISPLAY 0.872340 (2550 3625);
DISPLAY INVISIBLE (2550 3625);
FORCEPROP 1 LAST PATH I162
J 0
(2223 3750);
DISPLAY 0.872340 (2223 3750);
PAINT GREEN (2223 3750);
DISPLAY INVISIBLE (2223 3750);
FORCEADD TAP..1
(2225 3950);
FORCEPROP 3 LASTPIN (2175 3950) SIG_NAME M_D_CPU0_SA_DQS_DN<7>
J 0
(2185 3960);
DISPLAY 0.659574 (2185 3960);
PAINT MONO (2185 3960);
DISPLAY INVISIBLE (2185 3960);
FORCEPROP 1 LASTPIN (2175 3950) BN 7
J 0
(2163 3958);
DISPLAY 0.680851 (2163 3958);
PAINT GREEN (2163 3958);
FORCEPROP 2 LAST CDS_LIB standard
J 0
(2225 3950);
DISPLAY INVISIBLE (2225 3950);
FORCEPROP 1 LAST BODY_TYPE PLUMBING
J 0
(2225 4000);
DISPLAY 0.872340 (2225 4000);
PAINT GREEN (2225 4000);
DISPLAY INVISIBLE (2225 4000);
FORCEPROP 1 LAST HDL_TAP TRUE
J 0
(2550 3825);
DISPLAY 0.872340 (2550 3825);
DISPLAY INVISIBLE (2550 3825);
FORCEPROP 1 LAST PATH I163
J 0
(2223 3950);
DISPLAY 0.872340 (2223 3950);
PAINT GREEN (2223 3950);
DISPLAY INVISIBLE (2223 3950);
FORCEADD TAP..1
(2225 3850);
FORCEPROP 3 LASTPIN (2175 3850) SIG_NAME M_D_CPU0_SA_DQS_DN<6>
J 0
(2185 3860);
DISPLAY 0.659574 (2185 3860);
PAINT MONO (2185 3860);
DISPLAY INVISIBLE (2185 3860);
FORCEPROP 1 LASTPIN (2175 3850) BN 6
J 0
(2163 3858);
DISPLAY 0.680851 (2163 3858);
PAINT GREEN (2163 3858);
FORCEPROP 2 LAST CDS_LIB standard
J 0
(2225 3850);
DISPLAY INVISIBLE (2225 3850);
FORCEPROP 1 LAST BODY_TYPE PLUMBING
J 0
(2225 3900);
DISPLAY 0.872340 (2225 3900);
PAINT GREEN (2225 3900);
DISPLAY INVISIBLE (2225 3900);
FORCEPROP 1 LAST HDL_TAP TRUE
J 0
(2550 3725);
DISPLAY 0.872340 (2550 3725);
DISPLAY INVISIBLE (2550 3725);
FORCEPROP 1 LAST PATH I164
J 0
(2223 3850);
DISPLAY 0.872340 (2223 3850);
PAINT GREEN (2223 3850);
DISPLAY INVISIBLE (2223 3850);
FORCEADD TAP..1
(2225 4050);
FORCEPROP 3 LASTPIN (2175 4050) SIG_NAME M_D_CPU0_SA_DQS_DN<8>
J 0
(2185 4060);
DISPLAY 0.659574 (2185 4060);
PAINT MONO (2185 4060);
DISPLAY INVISIBLE (2185 4060);
FORCEPROP 1 LASTPIN (2175 4050) BN 8
J 0
(2163 4058);
DISPLAY 0.680851 (2163 4058);
PAINT GREEN (2163 4058);
FORCEPROP 2 LAST CDS_LIB standard
J 0
(2225 4050);
DISPLAY INVISIBLE (2225 4050);
FORCEPROP 1 LAST BODY_TYPE PLUMBING
J 0
(2225 4100);
DISPLAY 0.872340 (2225 4100);
PAINT GREEN (2225 4100);
DISPLAY INVISIBLE (2225 4100);
FORCEPROP 1 LAST HDL_TAP TRUE
J 0
(2550 3925);
DISPLAY 0.872340 (2550 3925);
DISPLAY INVISIBLE (2550 3925);
FORCEPROP 1 LAST PATH I165
J 0
(2223 4050);
DISPLAY 0.872340 (2223 4050);
PAINT GREEN (2223 4050);
DISPLAY INVISIBLE (2223 4050);
FORCEADD OFFPAGE..2
(3175 3175);
FORCEPROP 2 LAST $XR1 88 
J 0
(3454 3175);
DISPLAY 0.638298 (3454 3175);
PAINT MONO (3454 3175);
FORCEPROP 2 LAST $XR0 23 
J 0
(3364 3175);
DISPLAY 0.638298 (3364 3175);
PAINT MONO (3364 3175);
FORCEPROP 2 LAST CDS_LIB standard
J 0
(3175 3175);
PAINT MONO (3175 3175);
DISPLAY INVISIBLE (3175 3175);
FORCEPROP 1 LAST OFFPAGE TRUE
J 0
(3500 3050);
DISPLAY 1.170213 (3500 3050);
PAINT GREEN (3500 3050);
DISPLAY INVISIBLE (3500 3050);
FORCEPROP 1 LAST COMMENT_BODY TRUE
J 0
(3130 3080);
DISPLAY 1.170213 (3130 3080);
PAINT GREEN (3130 3080);
DISPLAY INVISIBLE (3130 3080);
FORCEPROP 2 LAST PATH I166
J 0
(3350 3250);
DISPLAY 1.021277 (3350 3250);
DISPLAY INVISIBLE (3350 3250);
FORCEADD OFFPAGE..2
(3175 3125);
FORCEPROP 2 LAST $XR1 88 
J 0
(3454 3125);
DISPLAY 0.638298 (3454 3125);
PAINT MONO (3454 3125);
FORCEPROP 2 LAST $XR0 23 
J 0
(3364 3125);
DISPLAY 0.638298 (3364 3125);
PAINT MONO (3364 3125);
FORCEPROP 2 LAST CDS_LIB standard
J 0
(3175 3125);
PAINT MONO (3175 3125);
DISPLAY INVISIBLE (3175 3125);
FORCEPROP 1 LAST OFFPAGE TRUE
J 0
(3500 3000);
DISPLAY 1.170213 (3500 3000);
PAINT GREEN (3500 3000);
DISPLAY INVISIBLE (3500 3000);
FORCEPROP 1 LAST COMMENT_BODY TRUE
J 0
(3130 3030);
DISPLAY 1.170213 (3130 3030);
PAINT GREEN (3130 3030);
DISPLAY INVISIBLE (3130 3030);
FORCEPROP 2 LAST PATH I167
J 0
(3350 3200);
DISPLAY 1.021277 (3350 3200);
DISPLAY INVISIBLE (3350 3200);
FORCEADD OFFPAGE..3
(125 4225);
FORCEPROP 2 LAST $XR1 88 
J 0
(429 4225);
DISPLAY 0.638298 (429 4225);
PAINT MONO (429 4225);
FORCEPROP 2 LAST $XR0 23 
J 0
(339 4225);
DISPLAY 0.638298 (339 4225);
PAINT MONO (339 4225);
FORCEPROP 2 LAST CDS_LIB standard
J 2
(125 4225);
DISPLAY INVISIBLE (125 4225);
FORCEPROP 1 LAST OFFPAGE TRUE
J 0
(450 4100);
DISPLAY 0.872340 (450 4100);
DISPLAY INVISIBLE (450 4100);
FORCEPROP 1 LAST COMMENT_BODY TRUE
J 0
(75 4125);
DISPLAY 0.872340 (75 4125);
PAINT GREEN (75 4125);
DISPLAY INVISIBLE (75 4125);
FORCEPROP 2 LAST PATH I168
J 0
(325 4300);
DISPLAY 1.021277 (325 4300);
DISPLAY INVISIBLE (325 4300);
FORCEADD TAP..1
(2050 4200);
FORCEPROP 3 LASTPIN (2000 4200) SIG_NAME M_D_CPU0_SA_DQS_DP<9>
J 0
(2010 4210);
DISPLAY 0.659574 (2010 4210);
PAINT MONO (2010 4210);
DISPLAY INVISIBLE (2010 4210);
FORCEPROP 1 LASTPIN (2000 4200) BN 9
J 0
(1988 4208);
DISPLAY 0.680851 (1988 4208);
PAINT GREEN (1988 4208);
FORCEPROP 2 LAST CDS_LIB standard
J 0
(2050 4200);
DISPLAY INVISIBLE (2050 4200);
FORCEPROP 1 LAST BODY_TYPE PLUMBING
J 0
(2050 4250);
DISPLAY 0.872340 (2050 4250);
PAINT GREEN (2050 4250);
DISPLAY INVISIBLE (2050 4250);
FORCEPROP 1 LAST HDL_TAP TRUE
J 0
(2375 4075);
DISPLAY 0.872340 (2375 4075);
DISPLAY INVISIBLE (2375 4075);
FORCEPROP 1 LAST PATH I169
J 0
(2048 4200);
DISPLAY 0.872340 (2048 4200);
PAINT GREEN (2048 4200);
DISPLAY INVISIBLE (2048 4200);
FORCEADD OFFPAGE..1
(-3275 3100);
FORCEPROP 2 LAST $XR0 23 
J 0
(-3496 3100);
DISPLAY 0.638298 (-3496 3100);
PAINT MONO (-3496 3100);
FORCEPROP 2 LAST CDS_LIB standard
J 0
(-3275 3100);
PAINT MONO (-3275 3100);
DISPLAY INVISIBLE (-3275 3100);
FORCEPROP 1 LAST OFFPAGE TRUE
J 0
(-2950 2975);
DISPLAY 0.872340 (-2950 2975);
DISPLAY INVISIBLE (-2950 2975);
FORCEPROP 1 LAST COMMENT_BODY TRUE
J 0
(-3150 3000);
DISPLAY 0.872340 (-3150 3000);
PAINT GREEN (-3150 3000);
DISPLAY INVISIBLE (-3150 3000);
FORCEPROP 2 LAST PATH I17
J 0
(-3225 3175);
DISPLAY 1.021277 (-3225 3175);
DISPLAY INVISIBLE (-3225 3175);
FORCEADD TAP..1
(2050 4100);
FORCEPROP 3 LASTPIN (2000 4100) SIG_NAME M_D_CPU0_SA_DQS_DP<8>
J 0
(2010 4110);
DISPLAY 0.659574 (2010 4110);
PAINT MONO (2010 4110);
DISPLAY INVISIBLE (2010 4110);
FORCEPROP 1 LASTPIN (2000 4100) BN 8
J 0
(1988 4108);
DISPLAY 0.680851 (1988 4108);
PAINT GREEN (1988 4108);
FORCEPROP 2 LAST CDS_LIB standard
J 0
(2050 4100);
DISPLAY INVISIBLE (2050 4100);
FORCEPROP 1 LAST BODY_TYPE PLUMBING
J 0
(2050 4150);
DISPLAY 0.872340 (2050 4150);
PAINT GREEN (2050 4150);
DISPLAY INVISIBLE (2050 4150);
FORCEPROP 1 LAST HDL_TAP TRUE
J 0
(2375 3975);
DISPLAY 0.872340 (2375 3975);
DISPLAY INVISIBLE (2375 3975);
FORCEPROP 1 LAST PATH I170
J 0
(2048 4100);
DISPLAY 0.872340 (2048 4100);
PAINT GREEN (2048 4100);
DISPLAY INVISIBLE (2048 4100);
FORCEADD TAP..1
(2225 4150);
FORCEPROP 3 LASTPIN (2175 4150) SIG_NAME M_D_CPU0_SA_DQS_DN<9>
J 0
(2185 4160);
DISPLAY 0.659574 (2185 4160);
PAINT MONO (2185 4160);
DISPLAY INVISIBLE (2185 4160);
FORCEPROP 1 LASTPIN (2175 4150) BN 9
J 0
(2163 4158);
DISPLAY 0.680851 (2163 4158);
PAINT GREEN (2163 4158);
FORCEPROP 2 LAST CDS_LIB standard
J 0
(2225 4150);
DISPLAY INVISIBLE (2225 4150);
FORCEPROP 1 LAST BODY_TYPE PLUMBING
J 0
(2225 4200);
DISPLAY 0.872340 (2225 4200);
PAINT GREEN (2225 4200);
DISPLAY INVISIBLE (2225 4200);
FORCEPROP 1 LAST HDL_TAP TRUE
J 0
(2550 4025);
DISPLAY 0.872340 (2550 4025);
DISPLAY INVISIBLE (2550 4025);
FORCEPROP 1 LAST PATH I171
J 0
(2223 4150);
DISPLAY 0.872340 (2223 4150);
PAINT GREEN (2223 4150);
DISPLAY INVISIBLE (2223 4150);
FORCEADD OFFPAGE..2
(3175 4225);
FORCEPROP 2 LAST $XR1 88 
J 0
(3454 4225);
DISPLAY 0.638298 (3454 4225);
PAINT MONO (3454 4225);
FORCEPROP 2 LAST $XR0 23 
J 0
(3364 4225);
DISPLAY 0.638298 (3364 4225);
PAINT MONO (3364 4225);
FORCEPROP 2 LAST CDS_LIB standard
J 0
(3175 4225);
PAINT MONO (3175 4225);
DISPLAY INVISIBLE (3175 4225);
FORCEPROP 1 LAST OFFPAGE TRUE
J 0
(3500 4100);
DISPLAY 1.170213 (3500 4100);
PAINT GREEN (3500 4100);
DISPLAY INVISIBLE (3500 4100);
FORCEPROP 1 LAST COMMENT_BODY TRUE
J 0
(3130 4130);
DISPLAY 1.170213 (3130 4130);
PAINT GREEN (3130 4130);
DISPLAY INVISIBLE (3130 4130);
FORCEPROP 2 LAST PATH I172
J 0
(3350 4300);
DISPLAY 1.021277 (3350 4300);
DISPLAY INVISIBLE (3350 4300);
FORCEADD OFFPAGE..2
(3175 4175);
FORCEPROP 2 LAST $XR1 88 
J 0
(3454 4175);
DISPLAY 0.638298 (3454 4175);
PAINT MONO (3454 4175);
FORCEPROP 2 LAST $XR0 23 
J 0
(3364 4175);
DISPLAY 0.638298 (3364 4175);
PAINT MONO (3364 4175);
FORCEPROP 2 LAST CDS_LIB standard
J 0
(3175 4175);
PAINT MONO (3175 4175);
DISPLAY INVISIBLE (3175 4175);
FORCEPROP 1 LAST OFFPAGE TRUE
J 0
(3500 4050);
DISPLAY 1.170213 (3500 4050);
PAINT GREEN (3500 4050);
DISPLAY INVISIBLE (3500 4050);
FORCEPROP 1 LAST COMMENT_BODY TRUE
J 0
(3130 4080);
DISPLAY 1.170213 (3130 4080);
PAINT GREEN (3130 4080);
DISPLAY INVISIBLE (3130 4080);
FORCEPROP 2 LAST PATH I173
J 0
(3350 4250);
DISPLAY 1.021277 (3350 4250);
DISPLAY INVISIBLE (3350 4250);
FORCEADD VCC_CORE..1
(3725 4750);
FORCEPROP 3 LASTPIN (3725 4700) SIG_NAME P12V_S3_AUX_CPU0_NVDIMM\g
J 0
(3735 4710);
DISPLAY 0.659574 (3735 4710);
PAINT MONO (3735 4710);
DISPLAY INVISIBLE (3735 4710);
FORCEPROP 1 LAST HDL_POWER P12V_S3_AUX_CPU0_NVDIMM
J 1
(3725 4800);
DISPLAY 1.148936 (3725 4800);
PAINT GREEN (3725 4800);
FORCEPROP 2 LAST CDS_LIB logical_power
J 0
(3725 4750);
PAINT MONO (3725 4750);
DISPLAY INVISIBLE (3725 4750);
FORCEPROP 1 LAST PATH I174
J 0
(3775 4775);
DISPLAY 0.872340 (3775 4775);
PAINT AQUA (3775 4775);
DISPLAY INVISIBLE (3775 4775);
FORCEADD SCONN288_ADR50017P087CC..3
(4575 2575);
FORCEPROP 1 LAST PART_NUMBER DFHST8FS460
J 0
(4120 4499);
DISPLAY 0.723404 (4120 4499);
PAINT GREEN (4120 4499);
DISPLAY INVISIBLE (4120 4499);
FORCEPROP 1 LAST MATERIAL IO
J 0
(4120 4372);
DISPLAY 0.723404 (4120 4372);
PAINT GREEN (4120 4372);
FORCEPROP 2 LAST PART_TYPE SMLF
J 0
(4125 4650);
DISPLAY 1.021277 (4125 4650);
FORCEPROP 2 LAST VALUE SCONN288_ADR50017-P087CC
J 0
(4125 4600);
DISPLAY 1.021277 (4125 4600);
FORCEPROP 1 LAST $LOCATION J8
J 0
(4125 4550);
DISPLAY 0.723404 (4125 4550);
PAINT GREEN (4125 4550);
FORCEPROP 0 LASTPIN (5175 950) $PN G1
J 0
(5185 960);
DISPLAY 0.680851 (5185 960);
PAINT MONO (5185 960);
FORCEPROP 0 LASTPIN (5175 900) $PN G2
J 0
(5185 910);
DISPLAY 0.680851 (5185 910);
PAINT MONO (5185 910);
FORCEPROP 0 LASTPIN (5175 850) $PN G3
J 0
(5185 860);
DISPLAY 0.680851 (5185 860);
PAINT MONO (5185 860);
FORCEPROP 0 LASTPIN (3975 4100) $PN 1
J 2
(3965 4110);
DISPLAY 0.680851 (3965 4110);
PAINT MONO (3965 4110);
FORCEPROP 0 LASTPIN (3975 4150) $PN 145
J 2
(3965 4160);
DISPLAY 0.680851 (3965 4160);
PAINT MONO (3965 4160);
FORCEPROP 0 LASTPIN (3975 4200) $PN 146
J 2
(3965 4210);
DISPLAY 0.680851 (3965 4210);
PAINT MONO (3965 4210);
FORCEPROP 0 LASTPIN (5175 1050) $PN 6
J 0
(5185 1060);
DISPLAY 0.680851 (5185 1060);
PAINT MONO (5185 1060);
FORCEPROP 0 LASTPIN (5175 1100) $PN 8
J 0
(5185 1110);
DISPLAY 0.680851 (5185 1110);
PAINT MONO (5185 1110);
FORCEPROP 0 LASTPIN (5175 1150) $PN 10
J 0
(5185 1160);
DISPLAY 0.680851 (5185 1160);
PAINT MONO (5185 1160);
FORCEPROP 0 LASTPIN (5175 1200) $PN 13
J 0
(5185 1210);
DISPLAY 0.680851 (5185 1210);
PAINT MONO (5185 1210);
FORCEPROP 0 LASTPIN (5175 1250) $PN 15
J 0
(5185 1260);
DISPLAY 0.680851 (5185 1260);
PAINT MONO (5185 1260);
FORCEPROP 0 LASTPIN (5175 1300) $PN 17
J 0
(5185 1310);
DISPLAY 0.680851 (5185 1310);
PAINT MONO (5185 1310);
FORCEPROP 0 LASTPIN (5175 1350) $PN 19
J 0
(5185 1360);
DISPLAY 0.680851 (5185 1360);
PAINT MONO (5185 1360);
FORCEPROP 0 LASTPIN (5175 1400) $PN 21
J 0
(5185 1410);
DISPLAY 0.680851 (5185 1410);
PAINT MONO (5185 1410);
FORCEPROP 0 LASTPIN (5175 1450) $PN 24
J 0
(5185 1460);
DISPLAY 0.680851 (5185 1460);
PAINT MONO (5185 1460);
FORCEPROP 0 LASTPIN (5175 1500) $PN 26
J 0
(5185 1510);
DISPLAY 0.680851 (5185 1510);
PAINT MONO (5185 1510);
FORCEPROP 0 LASTPIN (5175 1550) $PN 28
J 0
(5185 1560);
DISPLAY 0.680851 (5185 1560);
PAINT MONO (5185 1560);
FORCEPROP 0 LASTPIN (5175 1600) $PN 30
J 0
(5185 1610);
DISPLAY 0.680851 (5185 1610);
PAINT MONO (5185 1610);
FORCEPROP 0 LASTPIN (5175 1650) $PN 32
J 0
(5185 1660);
DISPLAY 0.680851 (5185 1660);
PAINT MONO (5185 1660);
FORCEPROP 0 LASTPIN (5175 1700) $PN 35
J 0
(5185 1710);
DISPLAY 0.680851 (5185 1710);
PAINT MONO (5185 1710);
FORCEPROP 0 LASTPIN (5175 1750) $PN 37
J 0
(5185 1760);
DISPLAY 0.680851 (5185 1760);
PAINT MONO (5185 1760);
FORCEPROP 0 LASTPIN (5175 1800) $PN 39
J 0
(5185 1810);
DISPLAY 0.680851 (5185 1810);
PAINT MONO (5185 1810);
FORCEPROP 0 LASTPIN (5175 1850) $PN 41
J 0
(5185 1860);
DISPLAY 0.680851 (5185 1860);
PAINT MONO (5185 1860);
FORCEPROP 0 LASTPIN (5175 1900) $PN 43
J 0
(5185 1910);
DISPLAY 0.680851 (5185 1910);
PAINT MONO (5185 1910);
FORCEPROP 0 LASTPIN (5175 1950) $PN 46
J 0
(5185 1960);
DISPLAY 0.680851 (5185 1960);
PAINT MONO (5185 1960);
FORCEPROP 0 LASTPIN (5175 2000) $PN 48
J 0
(5185 2010);
DISPLAY 0.680851 (5185 2010);
PAINT MONO (5185 2010);
FORCEPROP 0 LASTPIN (5175 2050) $PN 50
J 0
(5185 2060);
DISPLAY 0.680851 (5185 2060);
PAINT MONO (5185 2060);
FORCEPROP 0 LASTPIN (5175 2100) $PN 52
J 0
(5185 2110);
DISPLAY 0.680851 (5185 2110);
PAINT MONO (5185 2110);
FORCEPROP 0 LASTPIN (5175 2150) $PN 54
J 0
(5185 2160);
DISPLAY 0.680851 (5185 2160);
PAINT MONO (5185 2160);
FORCEPROP 0 LASTPIN (5175 2200) $PN 57
J 0
(5185 2210);
DISPLAY 0.680851 (5185 2210);
PAINT MONO (5185 2210);
FORCEPROP 0 LASTPIN (5175 2250) $PN 59
J 0
(5185 2260);
DISPLAY 0.680851 (5185 2260);
PAINT MONO (5185 2260);
FORCEPROP 0 LASTPIN (5175 2300) $PN 61
J 0
(5185 2310);
DISPLAY 0.680851 (5185 2310);
PAINT MONO (5185 2310);
FORCEPROP 0 LASTPIN (5175 2350) $PN 63
J 0
(5185 2360);
DISPLAY 0.680851 (5185 2360);
PAINT MONO (5185 2360);
FORCEPROP 0 LASTPIN (5175 2400) $PN 65
J 0
(5185 2410);
DISPLAY 0.680851 (5185 2410);
PAINT MONO (5185 2410);
FORCEPROP 0 LASTPIN (5175 2450) $PN 67
J 0
(5185 2460);
DISPLAY 0.680851 (5185 2460);
PAINT MONO (5185 2460);
FORCEPROP 0 LASTPIN (5175 2500) $PN 69
J 0
(5185 2510);
DISPLAY 0.680851 (5185 2510);
PAINT MONO (5185 2510);
FORCEPROP 0 LASTPIN (5175 2550) $PN 71
J 0
(5185 2560);
DISPLAY 0.680851 (5185 2560);
PAINT MONO (5185 2560);
FORCEPROP 0 LASTPIN (5175 2600) $PN 73
J 0
(5185 2610);
DISPLAY 0.680851 (5185 2610);
PAINT MONO (5185 2610);
FORCEPROP 0 LASTPIN (5175 2650) $PN 75
J 0
(5185 2660);
DISPLAY 0.680851 (5185 2660);
PAINT MONO (5185 2660);
FORCEPROP 0 LASTPIN (5175 2700) $PN 77
J 0
(5185 2710);
DISPLAY 0.680851 (5185 2710);
PAINT MONO (5185 2710);
FORCEPROP 0 LASTPIN (5175 2750) $PN 79
J 0
(5185 2760);
DISPLAY 0.680851 (5185 2760);
PAINT MONO (5185 2760);
FORCEPROP 0 LASTPIN (5175 2800) $PN 81
J 0
(5185 2810);
DISPLAY 0.680851 (5185 2810);
PAINT MONO (5185 2810);
FORCEPROP 0 LASTPIN (5175 2850) $PN 83
J 0
(5185 2860);
DISPLAY 0.680851 (5185 2860);
PAINT MONO (5185 2860);
FORCEPROP 0 LASTPIN (5175 2900) $PN 85
J 0
(5185 2910);
DISPLAY 0.680851 (5185 2910);
PAINT MONO (5185 2910);
FORCEPROP 0 LASTPIN (5175 2950) $PN 88
J 0
(5185 2960);
DISPLAY 0.680851 (5185 2960);
PAINT MONO (5185 2960);
FORCEPROP 0 LASTPIN (5175 3000) $PN 90
J 0
(5185 3010);
DISPLAY 0.680851 (5185 3010);
PAINT MONO (5185 3010);
FORCEPROP 0 LASTPIN (5175 3050) $PN 92
J 0
(5185 3060);
DISPLAY 0.680851 (5185 3060);
PAINT MONO (5185 3060);
FORCEPROP 0 LASTPIN (5175 3100) $PN 95
J 0
(5185 3110);
DISPLAY 0.680851 (5185 3110);
PAINT MONO (5185 3110);
FORCEPROP 0 LASTPIN (5175 3150) $PN 97
J 0
(5185 3160);
DISPLAY 0.680851 (5185 3160);
PAINT MONO (5185 3160);
FORCEPROP 0 LASTPIN (5175 3200) $PN 99
J 0
(5185 3210);
DISPLAY 0.680851 (5185 3210);
PAINT MONO (5185 3210);
FORCEPROP 0 LASTPIN (5175 3250) $PN 101
J 0
(5185 3260);
DISPLAY 0.680851 (5185 3260);
PAINT MONO (5185 3260);
FORCEPROP 0 LASTPIN (5175 3300) $PN 103
J 0
(5185 3310);
DISPLAY 0.680851 (5185 3310);
PAINT MONO (5185 3310);
FORCEPROP 0 LASTPIN (5175 3350) $PN 106
J 0
(5185 3360);
DISPLAY 0.680851 (5185 3360);
PAINT MONO (5185 3360);
FORCEPROP 0 LASTPIN (5175 3400) $PN 108
J 0
(5185 3410);
DISPLAY 0.680851 (5185 3410);
PAINT MONO (5185 3410);
FORCEPROP 0 LASTPIN (5175 3450) $PN 110
J 0
(5185 3460);
DISPLAY 0.680851 (5185 3460);
PAINT MONO (5185 3460);
FORCEPROP 0 LASTPIN (5175 3500) $PN 112
J 0
(5185 3510);
DISPLAY 0.680851 (5185 3510);
PAINT MONO (5185 3510);
FORCEPROP 0 LASTPIN (5175 3550) $PN 114
J 0
(5185 3560);
DISPLAY 0.680851 (5185 3560);
PAINT MONO (5185 3560);
FORCEPROP 0 LASTPIN (5175 3600) $PN 117
J 0
(5185 3610);
DISPLAY 0.680851 (5185 3610);
PAINT MONO (5185 3610);
FORCEPROP 0 LASTPIN (5175 3650) $PN 119
J 0
(5185 3660);
DISPLAY 0.680851 (5185 3660);
PAINT MONO (5185 3660);
FORCEPROP 0 LASTPIN (5175 3700) $PN 121
J 0
(5185 3710);
DISPLAY 0.680851 (5185 3710);
PAINT MONO (5185 3710);
FORCEPROP 0 LASTPIN (5175 3750) $PN 123
J 0
(5185 3760);
DISPLAY 0.680851 (5185 3760);
PAINT MONO (5185 3760);
FORCEPROP 0 LASTPIN (5175 3800) $PN 125
J 0
(5185 3810);
DISPLAY 0.680851 (5185 3810);
PAINT MONO (5185 3810);
FORCEPROP 0 LASTPIN (5175 3850) $PN 128
J 0
(5185 3860);
DISPLAY 0.680851 (5185 3860);
PAINT MONO (5185 3860);
FORCEPROP 0 LASTPIN (5175 3900) $PN 130
J 0
(5185 3910);
DISPLAY 0.680851 (5185 3910);
PAINT MONO (5185 3910);
FORCEPROP 0 LASTPIN (5175 3950) $PN 132
J 0
(5185 3960);
DISPLAY 0.680851 (5185 3960);
PAINT MONO (5185 3960);
FORCEPROP 0 LASTPIN (5175 4000) $PN 134
J 0
(5185 4010);
DISPLAY 0.680851 (5185 4010);
PAINT MONO (5185 4010);
FORCEPROP 0 LASTPIN (5175 4050) $PN 136
J 0
(5185 4060);
DISPLAY 0.680851 (5185 4060);
PAINT MONO (5185 4060);
FORCEPROP 0 LASTPIN (5175 4100) $PN 139
J 0
(5185 4110);
DISPLAY 0.680851 (5185 4110);
PAINT MONO (5185 4110);
FORCEPROP 0 LASTPIN (5175 4150) $PN 141
J 0
(5185 4160);
DISPLAY 0.680851 (5185 4160);
PAINT MONO (5185 4160);
FORCEPROP 0 LASTPIN (5175 4200) $PN 143
J 0
(5185 4210);
DISPLAY 0.680851 (5185 4210);
PAINT MONO (5185 4210);
FORCEPROP 0 LASTPIN (3975 950) $PN 151
J 2
(3965 960);
DISPLAY 0.680851 (3965 960);
PAINT MONO (3965 960);
FORCEPROP 0 LASTPIN (3975 1000) $PN 153
J 2
(3965 1010);
DISPLAY 0.680851 (3965 1010);
PAINT MONO (3965 1010);
FORCEPROP 0 LASTPIN (3975 1050) $PN 155
J 2
(3965 1060);
DISPLAY 0.680851 (3965 1060);
PAINT MONO (3965 1060);
FORCEPROP 0 LASTPIN (3975 1100) $PN 158
J 2
(3965 1110);
DISPLAY 0.680851 (3965 1110);
PAINT MONO (3965 1110);
FORCEPROP 0 LASTPIN (3975 1150) $PN 160
J 2
(3965 1160);
DISPLAY 0.680851 (3965 1160);
PAINT MONO (3965 1160);
FORCEPROP 0 LASTPIN (3975 1200) $PN 162
J 2
(3965 1210);
DISPLAY 0.680851 (3965 1210);
PAINT MONO (3965 1210);
FORCEPROP 0 LASTPIN (3975 1250) $PN 164
J 2
(3965 1260);
DISPLAY 0.680851 (3965 1260);
PAINT MONO (3965 1260);
FORCEPROP 0 LASTPIN (3975 1300) $PN 166
J 2
(3965 1310);
DISPLAY 0.680851 (3965 1310);
PAINT MONO (3965 1310);
FORCEPROP 0 LASTPIN (3975 1350) $PN 169
J 2
(3965 1360);
DISPLAY 0.680851 (3965 1360);
PAINT MONO (3965 1360);
FORCEPROP 0 LASTPIN (3975 1400) $PN 171
J 2
(3965 1410);
DISPLAY 0.680851 (3965 1410);
PAINT MONO (3965 1410);
FORCEPROP 0 LASTPIN (3975 1450) $PN 173
J 2
(3965 1460);
DISPLAY 0.680851 (3965 1460);
PAINT MONO (3965 1460);
FORCEPROP 0 LASTPIN (3975 1500) $PN 175
J 2
(3965 1510);
DISPLAY 0.680851 (3965 1510);
PAINT MONO (3965 1510);
FORCEPROP 0 LASTPIN (3975 1550) $PN 177
J 2
(3965 1560);
DISPLAY 0.680851 (3965 1560);
PAINT MONO (3965 1560);
FORCEPROP 0 LASTPIN (3975 1600) $PN 180
J 2
(3965 1610);
DISPLAY 0.680851 (3965 1610);
PAINT MONO (3965 1610);
FORCEPROP 0 LASTPIN (3975 1650) $PN 182
J 2
(3965 1660);
DISPLAY 0.680851 (3965 1660);
PAINT MONO (3965 1660);
FORCEPROP 0 LASTPIN (3975 1700) $PN 184
J 2
(3965 1710);
DISPLAY 0.680851 (3965 1710);
PAINT MONO (3965 1710);
FORCEPROP 0 LASTPIN (3975 1750) $PN 186
J 2
(3965 1760);
DISPLAY 0.680851 (3965 1760);
PAINT MONO (3965 1760);
FORCEPROP 0 LASTPIN (3975 1800) $PN 188
J 2
(3965 1810);
DISPLAY 0.680851 (3965 1810);
PAINT MONO (3965 1810);
FORCEPROP 0 LASTPIN (3975 1850) $PN 191
J 2
(3965 1860);
DISPLAY 0.680851 (3965 1860);
PAINT MONO (3965 1860);
FORCEPROP 0 LASTPIN (3975 1900) $PN 193
J 2
(3965 1910);
DISPLAY 0.680851 (3965 1910);
PAINT MONO (3965 1910);
FORCEPROP 0 LASTPIN (3975 1950) $PN 195
J 2
(3965 1960);
DISPLAY 0.680851 (3965 1960);
PAINT MONO (3965 1960);
FORCEPROP 0 LASTPIN (3975 2000) $PN 197
J 2
(3965 2010);
DISPLAY 0.680851 (3965 2010);
PAINT MONO (3965 2010);
FORCEPROP 0 LASTPIN (3975 2050) $PN 199
J 2
(3965 2060);
DISPLAY 0.680851 (3965 2060);
PAINT MONO (3965 2060);
FORCEPROP 0 LASTPIN (3975 2100) $PN 202
J 2
(3965 2110);
DISPLAY 0.680851 (3965 2110);
PAINT MONO (3965 2110);
FORCEPROP 0 LASTPIN (3975 2150) $PN 204
J 2
(3965 2160);
DISPLAY 0.680851 (3965 2160);
PAINT MONO (3965 2160);
FORCEPROP 0 LASTPIN (3975 2200) $PN 206
J 2
(3965 2210);
DISPLAY 0.680851 (3965 2210);
PAINT MONO (3965 2210);
FORCEPROP 0 LASTPIN (3975 2250) $PN 208
J 2
(3965 2260);
DISPLAY 0.680851 (3965 2260);
PAINT MONO (3965 2260);
FORCEPROP 0 LASTPIN (3975 2300) $PN 210
J 2
(3965 2310);
DISPLAY 0.680851 (3965 2310);
PAINT MONO (3965 2310);
FORCEPROP 0 LASTPIN (3975 2350) $PN 212
J 2
(3965 2360);
DISPLAY 0.680851 (3965 2360);
PAINT MONO (3965 2360);
FORCEPROP 0 LASTPIN (3975 2400) $PN 214
J 2
(3965 2410);
DISPLAY 0.680851 (3965 2410);
PAINT MONO (3965 2410);
FORCEPROP 0 LASTPIN (3975 2450) $PN 216
J 2
(3965 2460);
DISPLAY 0.680851 (3965 2460);
PAINT MONO (3965 2460);
FORCEPROP 0 LASTPIN (3975 2500) $PN 219
J 2
(3965 2510);
DISPLAY 0.680851 (3965 2510);
PAINT MONO (3965 2510);
FORCEPROP 0 LASTPIN (3975 2550) $PN 222
J 2
(3965 2560);
DISPLAY 0.680851 (3965 2560);
PAINT MONO (3965 2560);
FORCEPROP 0 LASTPIN (3975 2600) $PN 224
J 2
(3965 2610);
DISPLAY 0.680851 (3965 2610);
PAINT MONO (3965 2610);
FORCEPROP 0 LASTPIN (3975 2650) $PN 226
J 2
(3965 2660);
DISPLAY 0.680851 (3965 2660);
PAINT MONO (3965 2660);
FORCEPROP 0 LASTPIN (3975 2700) $PN 228
J 2
(3965 2710);
DISPLAY 0.680851 (3965 2710);
PAINT MONO (3965 2710);
FORCEPROP 0 LASTPIN (3975 2750) $PN 230
J 2
(3965 2760);
DISPLAY 0.680851 (3965 2760);
PAINT MONO (3965 2760);
FORCEPROP 0 LASTPIN (3975 2800) $PN 233
J 2
(3965 2810);
DISPLAY 0.680851 (3965 2810);
PAINT MONO (3965 2810);
FORCEPROP 0 LASTPIN (3975 2850) $PN 235
J 2
(3965 2860);
DISPLAY 0.680851 (3965 2860);
PAINT MONO (3965 2860);
FORCEPROP 0 LASTPIN (3975 2900) $PN 237
J 2
(3965 2910);
DISPLAY 0.680851 (3965 2910);
PAINT MONO (3965 2910);
FORCEPROP 0 LASTPIN (3975 2950) $PN 240
J 2
(3965 2960);
DISPLAY 0.680851 (3965 2960);
PAINT MONO (3965 2960);
FORCEPROP 0 LASTPIN (3975 3000) $PN 242
J 2
(3965 3010);
DISPLAY 0.680851 (3965 3010);
PAINT MONO (3965 3010);
FORCEPROP 0 LASTPIN (3975 3050) $PN 244
J 2
(3965 3060);
DISPLAY 0.680851 (3965 3060);
PAINT MONO (3965 3060);
FORCEPROP 0 LASTPIN (3975 3100) $PN 246
J 2
(3965 3110);
DISPLAY 0.680851 (3965 3110);
PAINT MONO (3965 3110);
FORCEPROP 0 LASTPIN (3975 3150) $PN 248
J 2
(3965 3160);
DISPLAY 0.680851 (3965 3160);
PAINT MONO (3965 3160);
FORCEPROP 0 LASTPIN (3975 3200) $PN 251
J 2
(3965 3210);
DISPLAY 0.680851 (3965 3210);
PAINT MONO (3965 3210);
FORCEPROP 0 LASTPIN (3975 3250) $PN 253
J 2
(3965 3260);
DISPLAY 0.680851 (3965 3260);
PAINT MONO (3965 3260);
FORCEPROP 0 LASTPIN (3975 3300) $PN 255
J 2
(3965 3310);
DISPLAY 0.680851 (3965 3310);
PAINT MONO (3965 3310);
FORCEPROP 0 LASTPIN (3975 3350) $PN 257
J 2
(3965 3360);
DISPLAY 0.680851 (3965 3360);
PAINT MONO (3965 3360);
FORCEPROP 0 LASTPIN (3975 3400) $PN 259
J 2
(3965 3410);
DISPLAY 0.680851 (3965 3410);
PAINT MONO (3965 3410);
FORCEPROP 0 LASTPIN (3975 3450) $PN 262
J 2
(3965 3460);
DISPLAY 0.680851 (3965 3460);
PAINT MONO (3965 3460);
FORCEPROP 0 LASTPIN (3975 3500) $PN 264
J 2
(3965 3510);
DISPLAY 0.680851 (3965 3510);
PAINT MONO (3965 3510);
FORCEPROP 0 LASTPIN (3975 3550) $PN 266
J 2
(3965 3560);
DISPLAY 0.680851 (3965 3560);
PAINT MONO (3965 3560);
FORCEPROP 0 LASTPIN (3975 3600) $PN 268
J 2
(3965 3610);
DISPLAY 0.680851 (3965 3610);
PAINT MONO (3965 3610);
FORCEPROP 0 LASTPIN (3975 3650) $PN 270
J 2
(3965 3660);
DISPLAY 0.680851 (3965 3660);
PAINT MONO (3965 3660);
FORCEPROP 0 LASTPIN (3975 3700) $PN 273
J 2
(3965 3710);
DISPLAY 0.680851 (3965 3710);
PAINT MONO (3965 3710);
FORCEPROP 0 LASTPIN (3975 3750) $PN 275
J 2
(3965 3760);
DISPLAY 0.680851 (3965 3760);
PAINT MONO (3965 3760);
FORCEPROP 0 LASTPIN (3975 3800) $PN 277
J 2
(3965 3810);
DISPLAY 0.680851 (3965 3810);
PAINT MONO (3965 3810);
FORCEPROP 0 LASTPIN (3975 3850) $PN 279
J 2
(3965 3860);
DISPLAY 0.680851 (3965 3860);
PAINT MONO (3965 3860);
FORCEPROP 0 LASTPIN (3975 3900) $PN 281
J 2
(3965 3910);
DISPLAY 0.680851 (3965 3910);
PAINT MONO (3965 3910);
FORCEPROP 0 LASTPIN (3975 3950) $PN 284
J 2
(3965 3960);
DISPLAY 0.680851 (3965 3960);
PAINT MONO (3965 3960);
FORCEPROP 0 LASTPIN (3975 4000) $PN 286
J 2
(3965 4010);
DISPLAY 0.680851 (3965 4010);
PAINT MONO (3965 4010);
FORCEPROP 0 LASTPIN (3975 4050) $PN 288
J 2
(3965 4060);
DISPLAY 0.680851 (3965 4060);
PAINT MONO (3965 4060);
FORCEPROP 1 LAST NEEDS_NO_SIZE TRUE
J 0
(4575 2575);
DISPLAY 0.723404 (4575 2575);
PAINT GREEN (4575 2575);
DISPLAY INVISIBLE (4575 2575);
FORCEPROP 1 LAST CDS_LMAN_SYM_OUTLINE -450,1775,450,-1775
J 0
(4575 2575);
DISPLAY 0.468085 (4575 2575);
PAINT GREEN (4575 2575);
DISPLAY INVISIBLE (4575 2575);
FORCEPROP 2 LAST CDS_LIB pure_quanta
J 0
(4575 2575);
DISPLAY INVISIBLE (4575 2575);
FORCEPROP 2 LAST CDS_LOCATION J8
J 0
(4125 4700);
DISPLAY 1.021277 (4125 4700);
DISPLAY INVISIBLE (4125 4700);
FORCEPROP 0 LAST $SEC 3
J 0
(4125 4700);
DISPLAY 0.680851 (4125 4700);
PAINT MONO (4125 4700);
DISPLAY INVISIBLE (4125 4700);
FORCEPROP 2 LAST CDS_SEC 3
J 0
(4125 4700);
DISPLAY 1.021277 (4125 4700);
DISPLAY INVISIBLE (4125 4700);
FORCEPROP 1 LAST PATH I175
J 0
(4575 2575);
DISPLAY 0.723404 (4575 2575);
PAINT GREEN (4575 2575);
DISPLAY INVISIBLE (4575 2575);
FORCEADD UNIVERSAL_GND..1
(5425 500);
FORCEPROP 3 LASTPIN (5425 550) SIG_NAME GND\g
J 0
(5435 560);
DISPLAY 0.659574 (5435 560);
PAINT MONO (5435 560);
DISPLAY INVISIBLE (5435 560);
FORCEPROP 2 LAST CDS_LIB logical_power
J 0
(5425 500);
PAINT MONO (5425 500);
DISPLAY INVISIBLE (5425 500);
FORCEPROP 1 LAST HDL_POWER GND
J 1
(5450 425);
DISPLAY 0.872340 (5450 425);
PAINT GREEN (5450 425);
DISPLAY INVISIBLE (5450 425);
FORCEPROP 1 LAST PATH I176
J 0
(5500 500);
DISPLAY 0.872340 (5500 500);
PAINT AQUA (5500 500);
DISPLAY INVISIBLE (5500 500);
FORCEADD OFFPAGE..3
R 2
(-3275 1350);
FORCEPROP 2 LAST $XR0 114 
J 0
(-3555 1350);
DISPLAY 0.638298 (-3555 1350);
PAINT MONO (-3555 1350);
FORCEPROP 2 LAST CDS_LIB standard
J 0
(-3275 1350);
PAINT MONO (-3275 1350);
DISPLAY INVISIBLE (-3275 1350);
FORCEPROP 1 LAST OFFPAGE TRUE
J 2
(-3600 1225);
DISPLAY 0.872340 (-3600 1225);
DISPLAY INVISIBLE (-3600 1225);
FORCEPROP 1 LAST COMMENT_BODY TRUE
J 2
(-3225 1250);
DISPLAY 0.872340 (-3225 1250);
PAINT GREEN (-3225 1250);
DISPLAY INVISIBLE (-3225 1250);
FORCEPROP 2 LAST PATH I177
J 0
(-3225 1425);
DISPLAY 1.021277 (-3225 1425);
DISPLAY INVISIBLE (-3225 1425);
FORCEADD SCONN288_ADR50017P087CC..2
(1150 3200);
FORCEPROP 1 LAST PART_NUMBER DFHST8FS460
J 0
(545 4488);
DISPLAY 0.723404 (545 4488);
PAINT GREEN (545 4488);
DISPLAY INVISIBLE (545 4488);
FORCEPROP 1 LAST MATERIAL IO
J 0
(545 4361);
DISPLAY 0.723404 (545 4361);
PAINT GREEN (545 4361);
FORCEPROP 2 LAST VALUE SCONN288_ADR50017-P087CC
J 0
(550 4675);
DISPLAY 1.021277 (550 4675);
FORCEPROP 2 LAST PART_TYPE SMLF
J 0
(550 4725);
DISPLAY 1.021277 (550 4725);
FORCEPROP 1 LAST LOCATION J8
J 0
(545 4635);
DISPLAY 0.723404 (545 4635);
PAINT GREEN (545 4635);
FORCEPROP 0 LASTPIN (1900 3250) $PN 12
J 0
(1910 3260);
DISPLAY 0.680851 (1910 3260);
PAINT MONO (1910 3260);
FORCEPROP 0 LASTPIN (1900 3300) $PN 11
J 0
(1910 3310);
DISPLAY 0.680851 (1910 3310);
PAINT MONO (1910 3310);
FORCEPROP 0 LASTPIN (1900 2200) $PN 105
J 0
(1910 2210);
DISPLAY 0.680851 (1910 2210);
PAINT MONO (1910 2210);
FORCEPROP 0 LASTPIN (1900 2250) $PN 104
J 0
(1910 2260);
DISPLAY 0.680851 (1910 2260);
PAINT MONO (1910 2260);
FORCEPROP 0 LASTPIN (1900 3350) $PN 23
J 0
(1910 3360);
DISPLAY 0.680851 (1910 3360);
PAINT MONO (1910 3360);
FORCEPROP 0 LASTPIN (1900 3400) $PN 22
J 0
(1910 3410);
DISPLAY 0.680851 (1910 3410);
PAINT MONO (1910 3410);
FORCEPROP 0 LASTPIN (1900 2300) $PN 116
J 0
(1910 2310);
DISPLAY 0.680851 (1910 2310);
PAINT MONO (1910 2310);
FORCEPROP 0 LASTPIN (1900 2350) $PN 115
J 0
(1910 2360);
DISPLAY 0.680851 (1910 2360);
PAINT MONO (1910 2360);
FORCEPROP 0 LASTPIN (1900 3450) $PN 34
J 0
(1910 3460);
DISPLAY 0.680851 (1910 3460);
PAINT MONO (1910 3460);
FORCEPROP 0 LASTPIN (1900 3500) $PN 33
J 0
(1910 3510);
DISPLAY 0.680851 (1910 3510);
PAINT MONO (1910 3510);
FORCEPROP 0 LASTPIN (1900 2400) $PN 127
J 0
(1910 2410);
DISPLAY 0.680851 (1910 2410);
PAINT MONO (1910 2410);
FORCEPROP 0 LASTPIN (1900 2450) $PN 126
J 0
(1910 2460);
DISPLAY 0.680851 (1910 2460);
PAINT MONO (1910 2460);
FORCEPROP 0 LASTPIN (1900 3550) $PN 45
J 0
(1910 3560);
DISPLAY 0.680851 (1910 3560);
PAINT MONO (1910 3560);
FORCEPROP 0 LASTPIN (1900 3600) $PN 44
J 0
(1910 3610);
DISPLAY 0.680851 (1910 3610);
PAINT MONO (1910 3610);
FORCEPROP 0 LASTPIN (1900 2500) $PN 138
J 0
(1910 2510);
DISPLAY 0.680851 (1910 2510);
PAINT MONO (1910 2510);
FORCEPROP 0 LASTPIN (1900 2550) $PN 137
J 0
(1910 2560);
DISPLAY 0.680851 (1910 2560);
PAINT MONO (1910 2560);
FORCEPROP 0 LASTPIN (1900 3650) $PN 56
J 0
(1910 3660);
DISPLAY 0.680851 (1910 3660);
PAINT MONO (1910 3660);
FORCEPROP 0 LASTPIN (1900 3700) $PN 55
J 0
(1910 3710);
DISPLAY 0.680851 (1910 3710);
PAINT MONO (1910 3710);
FORCEPROP 0 LASTPIN (1900 2600) $PN 238
J 0
(1910 2610);
DISPLAY 0.680851 (1910 2610);
PAINT MONO (1910 2610);
FORCEPROP 0 LASTPIN (1900 2650) $PN 239
J 0
(1910 2660);
DISPLAY 0.680851 (1910 2660);
PAINT MONO (1910 2660);
FORCEPROP 0 LASTPIN (1900 3750) $PN 156
J 0
(1910 3760);
DISPLAY 0.680851 (1910 3760);
PAINT MONO (1910 3760);
FORCEPROP 0 LASTPIN (1900 3800) $PN 157
J 0
(1910 3810);
DISPLAY 0.680851 (1910 3810);
PAINT MONO (1910 3810);
FORCEPROP 0 LASTPIN (1900 2700) $PN 249
J 0
(1910 2710);
DISPLAY 0.680851 (1910 2710);
PAINT MONO (1910 2710);
FORCEPROP 0 LASTPIN (1900 2750) $PN 250
J 0
(1910 2760);
DISPLAY 0.680851 (1910 2760);
PAINT MONO (1910 2760);
FORCEPROP 0 LASTPIN (1900 3850) $PN 167
J 0
(1910 3860);
DISPLAY 0.680851 (1910 3860);
PAINT MONO (1910 3860);
FORCEPROP 0 LASTPIN (1900 3900) $PN 168
J 0
(1910 3910);
DISPLAY 0.680851 (1910 3910);
PAINT MONO (1910 3910);
FORCEPROP 0 LASTPIN (1900 2800) $PN 260
J 0
(1910 2810);
DISPLAY 0.680851 (1910 2810);
PAINT MONO (1910 2810);
FORCEPROP 0 LASTPIN (1900 2850) $PN 261
J 0
(1910 2860);
DISPLAY 0.680851 (1910 2860);
PAINT MONO (1910 2860);
FORCEPROP 0 LASTPIN (1900 3950) $PN 178
J 0
(1910 3960);
DISPLAY 0.680851 (1910 3960);
PAINT MONO (1910 3960);
FORCEPROP 0 LASTPIN (1900 4000) $PN 179
J 0
(1910 4010);
DISPLAY 0.680851 (1910 4010);
PAINT MONO (1910 4010);
FORCEPROP 0 LASTPIN (1900 2900) $PN 271
J 0
(1910 2910);
DISPLAY 0.680851 (1910 2910);
PAINT MONO (1910 2910);
FORCEPROP 0 LASTPIN (1900 2950) $PN 272
J 0
(1910 2960);
DISPLAY 0.680851 (1910 2960);
PAINT MONO (1910 2960);
FORCEPROP 0 LASTPIN (1900 4050) $PN 189
J 0
(1910 4060);
DISPLAY 0.680851 (1910 4060);
PAINT MONO (1910 4060);
FORCEPROP 0 LASTPIN (1900 4100) $PN 190
J 0
(1910 4110);
DISPLAY 0.680851 (1910 4110);
PAINT MONO (1910 4110);
FORCEPROP 0 LASTPIN (1900 3000) $PN 282
J 0
(1910 3010);
DISPLAY 0.680851 (1910 3010);
PAINT MONO (1910 3010);
FORCEPROP 0 LASTPIN (1900 3050) $PN 283
J 0
(1910 3060);
DISPLAY 0.680851 (1910 3060);
PAINT MONO (1910 3060);
FORCEPROP 0 LASTPIN (1900 4150) $PN 200
J 0
(1910 4160);
DISPLAY 0.680851 (1910 4160);
PAINT MONO (1910 4160);
FORCEPROP 0 LASTPIN (1900 4200) $PN 201
J 0
(1910 4210);
DISPLAY 0.680851 (1910 4210);
PAINT MONO (1910 4210);
FORCEPROP 0 LASTPIN (1900 3100) $PN 94
J 0
(1910 3110);
DISPLAY 0.680851 (1910 3110);
PAINT MONO (1910 3110);
FORCEPROP 0 LASTPIN (1900 3150) $PN 93
J 0
(1910 3160);
DISPLAY 0.680851 (1910 3160);
PAINT MONO (1910 3160);
FORCEPROP 1 LAST NEEDS_NO_SIZE TRUE
J 0
(1150 3200);
DISPLAY 0.723404 (1150 3200);
PAINT GREEN (1150 3200);
DISPLAY INVISIBLE (1150 3200);
FORCEPROP 1 LAST CDS_LMAN_SYM_OUTLINE -600,1150,600,-1150
J 0
(1150 3200);
DISPLAY 0.468085 (1150 3200);
PAINT GREEN (1150 3200);
DISPLAY INVISIBLE (1150 3200);
FORCEPROP 2 LAST CDS_LIB pure_quanta
J 0
(1150 3200);
DISPLAY INVISIBLE (1150 3200);
FORCEPROP 0 LAST $SEC 2
J 0
(550 4775);
DISPLAY 0.680851 (550 4775);
PAINT MONO (550 4775);
DISPLAY INVISIBLE (550 4775);
FORCEPROP 0 LAST CDS_SEC 2
J 0
(550 4775);
DISPLAY 1.021277 (550 4775);
DISPLAY INVISIBLE (550 4775);
FORCEPROP 1 LAST PATH I178
J 0
(1150 3200);
DISPLAY 0.723404 (1150 3200);
PAINT GREEN (1150 3200);
DISPLAY INVISIBLE (1150 3200);
FORCEADD OFFPAGE..1
(-2125 1450);
FORCEPROP 2 LAST $XR7 88 
J 0
(-3007 1450);
DISPLAY 0.638298 (-3007 1450);
PAINT MONO (-3007 1450);
FORCEPROP 2 LAST $XR6 87 
J 0
(-2917 1450);
DISPLAY 0.638298 (-2917 1450);
PAINT MONO (-2917 1450);
FORCEPROP 2 LAST $XR5 86 
J 0
(-2827 1450);
DISPLAY 0.638298 (-2827 1450);
PAINT MONO (-2827 1450);
FORCEPROP 2 LAST $XR4 85 
J 0
(-2737 1450);
DISPLAY 0.638298 (-2737 1450);
PAINT MONO (-2737 1450);
FORCEPROP 2 LAST $XR3 84 
J 0
(-2647 1450);
DISPLAY 0.638298 (-2647 1450);
PAINT MONO (-2647 1450);
FORCEPROP 2 LAST $XR2 83 
J 0
(-2557 1450);
DISPLAY 0.638298 (-2557 1450);
PAINT MONO (-2557 1450);
FORCEPROP 2 LAST $XR1 82 
J 0
(-2467 1450);
DISPLAY 0.638298 (-2467 1450);
PAINT MONO (-2467 1450);
FORCEPROP 2 LAST $XR0 229 
J 0
(-2377 1450);
DISPLAY 0.638298 (-2377 1450);
PAINT MONO (-2377 1450);
FORCEPROP 2 LAST CDS_LIB standard
J 0
(-2125 1450);
PAINT MONO (-2125 1450);
DISPLAY INVISIBLE (-2125 1450);
FORCEPROP 1 LAST OFFPAGE TRUE
J 0
(-1800 1325);
DISPLAY 0.872340 (-1800 1325);
DISPLAY INVISIBLE (-1800 1325);
FORCEPROP 1 LAST COMMENT_BODY TRUE
J 0
(-2000 1350);
DISPLAY 0.872340 (-2000 1350);
PAINT GREEN (-2000 1350);
DISPLAY INVISIBLE (-2000 1350);
FORCEPROP 2 LAST PATH I179
J 2
(-2575 1500);
DISPLAY 1.021277 (-2575 1500);
DISPLAY INVISIBLE (-2575 1500);
FORCEADD OFFPAGE..1
(-3275 3050);
FORCEPROP 2 LAST $XR0 23 
J 0
(-3496 3050);
DISPLAY 0.638298 (-3496 3050);
PAINT MONO (-3496 3050);
FORCEPROP 2 LAST CDS_LIB standard
J 0
(-3275 3050);
PAINT MONO (-3275 3050);
DISPLAY INVISIBLE (-3275 3050);
FORCEPROP 1 LAST OFFPAGE TRUE
J 0
(-2950 2925);
DISPLAY 0.872340 (-2950 2925);
DISPLAY INVISIBLE (-2950 2925);
FORCEPROP 1 LAST COMMENT_BODY TRUE
J 0
(-3150 2950);
DISPLAY 0.872340 (-3150 2950);
PAINT GREEN (-3150 2950);
DISPLAY INVISIBLE (-3150 2950);
FORCEPROP 2 LAST PATH I18
J 0
(-3225 3125);
DISPLAY 1.021277 (-3225 3125);
DISPLAY INVISIBLE (-3225 3125);
FORCEADD Q_RES..1
(-3400 1525);
FORCEPROP 1 LAST PART_NUMBER CS04992FB07
J 0
(-3300 1500);
DISPLAY 0.404255 (-3300 1500);
DISPLAY INVISIBLE (-3300 1500);
FORCEPROP 1 LAST VALUE 49.9
J 2
(-3175 1525);
DISPLAY 0.510638 (-3175 1525);
FORCEPROP 1 LAST MATERIAL CHIP
J 0
(-3300 1475);
DISPLAY 0.404255 (-3300 1475);
FORCEPROP 1 LAST $LOCATION R3882
J 0
(-3625 1525);
DISPLAY 0.638298 (-3625 1525);
FORCEPROP 1 LASTPIN (-3500 1525) $PN 1
J 0
(-3488 1537);
DISPLAY 0.787234 (-3488 1537);
PAINT MONO (-3488 1537);
FORCEPROP 1 LASTPIN (-3300 1525) $PN 2
J 0
(-3338 1537);
DISPLAY 0.787234 (-3338 1537);
PAINT MONO (-3338 1537);
FORCEPROP 2 LAST CDS_LIB pure_quanta
J 0
(-3400 1525);
DISPLAY INVISIBLE (-3400 1525);
FORCEPROP 1 LAST PACK_TYPE 0402LF
J 0
(-3100 1525);
DISPLAY 0.510638 (-3100 1525);
DISPLAY INVISIBLE (-3100 1525);
FORCEPROP 1 LAST TOLERANCE 1%
J 0
(-3175 1525);
DISPLAY 0.510638 (-3175 1525);
DISPLAY INVISIBLE (-3175 1525);
FORCEPROP 1 LAST WATTAGE 1/16W
J 2
(-3100 1475);
DISPLAY 0.404255 (-3100 1475);
DISPLAY INVISIBLE (-3100 1475);
FORCEPROP 0 LAST CDS_LOCATION R3882
J 0
(-3525 1575);
DISPLAY 1.021277 (-3525 1575);
DISPLAY INVISIBLE (-3525 1575);
FORCEPROP 0 LAST $SEC 1
J 0
(-3525 1575);
DISPLAY 0.680851 (-3525 1575);
PAINT MONO (-3525 1575);
DISPLAY INVISIBLE (-3525 1575);
FORCEPROP 0 LAST CDS_SEC 1
J 0
(-3525 1575);
DISPLAY 1.021277 (-3525 1575);
DISPLAY INVISIBLE (-3525 1575);
FORCEPROP 1 LAST PATH I180
J 0
(-3450 1675);
DISPLAY 0.978723 (-3450 1675);
PAINT WHITE (-3450 1675);
DISPLAY INVISIBLE (-3450 1675);
FORCEADD OFFPAGE..1
(-3275 3250);
FORCEPROP 2 LAST $XR0 23 
J 0
(-3496 3250);
DISPLAY 0.638298 (-3496 3250);
PAINT MONO (-3496 3250);
FORCEPROP 2 LAST CDS_LIB standard
J 0
(-3275 3250);
PAINT MONO (-3275 3250);
DISPLAY INVISIBLE (-3275 3250);
FORCEPROP 1 LAST OFFPAGE TRUE
J 0
(-2950 3125);
DISPLAY 0.872340 (-2950 3125);
DISPLAY INVISIBLE (-2950 3125);
FORCEPROP 1 LAST COMMENT_BODY TRUE
J 0
(-3150 3150);
DISPLAY 0.872340 (-3150 3150);
PAINT GREEN (-3150 3150);
DISPLAY INVISIBLE (-3150 3150);
FORCEPROP 2 LAST PATH I19
J 0
(-3225 3325);
DISPLAY 1.021277 (-3225 3325);
DISPLAY INVISIBLE (-3225 3325);
FORCEADD Q_RES..2
(-2125 50);
FORCEPROP 1 LAST PART_NUMBER CS41962FB03
J 0
(-2085 -75);
DISPLAY 0.978723 (-2085 -75);
DISPLAY INVISIBLE (-2085 -75);
FORCEPROP 1 LAST WATTAGE 1/16W
J 0
(-2085 25);
DISPLAY 0.978723 (-2085 25);
FORCEPROP 1 LAST TOLERANCE 1%
J 0
(-2080 75);
DISPLAY 0.978723 (-2080 75);
FORCEPROP 1 LAST MATERIAL CHIP
J 0
(-2085 -25);
DISPLAY 0.978723 (-2085 -25);
FORCEPROP 1 LAST PACK_TYPE 0402LF
J 0
(-2085 -125);
DISPLAY 0.978723 (-2085 -125);
FORCEPROP 1 LAST VALUE 196K
J 0
(-2080 125);
DISPLAY 0.978723 (-2080 125);
FORCEPROP 1 LAST $LOCATION R33
J 0
(-2080 175);
DISPLAY 0.978723 (-2080 175);
FORCEPROP 1 LASTPIN (-2125 150) $PN 1
J 0
(-2120 112);
DISPLAY 0.787234 (-2120 112);
FORCEPROP 1 LASTPIN (-2125 -50) $PN 2
J 0
(-2120 -40);
DISPLAY 0.787234 (-2120 -40);
FORCEPROP 2 LAST CDS_LIB pure_quanta
J 0
(-2125 50);
PAINT MONO (-2125 50);
DISPLAY INVISIBLE (-2125 50);
FORCEPROP 2 LAST CDS_LOCATION R33
J 0
(-2075 275);
DISPLAY 1.021277 (-2075 275);
DISPLAY INVISIBLE (-2075 275);
FORCEPROP 2 LAST $SEC 1
J 0
(-2075 275);
DISPLAY 0.680851 (-2075 275);
PAINT MONO (-2075 275);
DISPLAY INVISIBLE (-2075 275);
FORCEPROP 2 LAST CDS_SEC 1
J 0
(-2075 275);
DISPLAY 1.021277 (-2075 275);
DISPLAY INVISIBLE (-2075 275);
FORCEPROP 1 LAST PATH I2
J 0
(-2075 225);
DISPLAY 0.978723 (-2075 225);
PAINT WHITE (-2075 225);
DISPLAY INVISIBLE (-2075 225);
FORCEADD OFFPAGE..1
(-3275 3200);
FORCEPROP 2 LAST $XR0 23 
J 0
(-3496 3200);
DISPLAY 0.638298 (-3496 3200);
PAINT MONO (-3496 3200);
FORCEPROP 2 LAST CDS_LIB standard
J 0
(-3275 3200);
PAINT MONO (-3275 3200);
DISPLAY INVISIBLE (-3275 3200);
FORCEPROP 1 LAST OFFPAGE TRUE
J 0
(-2950 3075);
DISPLAY 0.872340 (-2950 3075);
DISPLAY INVISIBLE (-2950 3075);
FORCEPROP 1 LAST COMMENT_BODY TRUE
J 0
(-3150 3100);
DISPLAY 0.872340 (-3150 3100);
PAINT GREEN (-3150 3100);
DISPLAY INVISIBLE (-3150 3100);
FORCEPROP 2 LAST PATH I20
J 0
(-3225 3275);
DISPLAY 1.021277 (-3225 3275);
DISPLAY INVISIBLE (-3225 3275);
FORCEADD OFFPAGE..1
(-3275 3350);
FORCEPROP 2 LAST $XR1 88 
J 0
(-3586 3350);
DISPLAY 0.638298 (-3586 3350);
PAINT MONO (-3586 3350);
FORCEPROP 2 LAST $XR0 23 
J 0
(-3496 3350);
DISPLAY 0.638298 (-3496 3350);
PAINT MONO (-3496 3350);
FORCEPROP 2 LAST CDS_LIB standard
J 0
(-3275 3350);
PAINT MONO (-3275 3350);
DISPLAY INVISIBLE (-3275 3350);
FORCEPROP 1 LAST OFFPAGE TRUE
J 0
(-2950 3225);
DISPLAY 0.872340 (-2950 3225);
DISPLAY INVISIBLE (-2950 3225);
FORCEPROP 1 LAST COMMENT_BODY TRUE
J 0
(-3150 3250);
DISPLAY 0.872340 (-3150 3250);
PAINT GREEN (-3150 3250);
DISPLAY INVISIBLE (-3150 3250);
FORCEPROP 2 LAST PATH I21
J 0
(-3225 3425);
DISPLAY 1.021277 (-3225 3425);
DISPLAY INVISIBLE (-3225 3425);
FORCEADD OFFPAGE..1
(-3275 3400);
FORCEPROP 2 LAST $XR1 88 
J 0
(-3586 3400);
DISPLAY 0.638298 (-3586 3400);
PAINT MONO (-3586 3400);
FORCEPROP 2 LAST $XR0 23 
J 0
(-3496 3400);
DISPLAY 0.638298 (-3496 3400);
PAINT MONO (-3496 3400);
FORCEPROP 2 LAST CDS_LIB standard
J 0
(-3275 3400);
PAINT MONO (-3275 3400);
DISPLAY INVISIBLE (-3275 3400);
FORCEPROP 1 LAST OFFPAGE TRUE
J 0
(-2950 3275);
DISPLAY 0.872340 (-2950 3275);
DISPLAY INVISIBLE (-2950 3275);
FORCEPROP 1 LAST COMMENT_BODY TRUE
J 0
(-3150 3300);
DISPLAY 0.872340 (-3150 3300);
PAINT GREEN (-3150 3300);
DISPLAY INVISIBLE (-3150 3300);
FORCEPROP 2 LAST PATH I22
J 0
(-3225 3475);
DISPLAY 1.021277 (-3225 3475);
DISPLAY INVISIBLE (-3225 3475);
FORCEADD OFFPAGE..1
(-3275 3825);
FORCEPROP 2 LAST $XR1 88 
J 0
(-3586 3825);
DISPLAY 0.638298 (-3586 3825);
PAINT MONO (-3586 3825);
FORCEPROP 2 LAST $XR0 23 
J 0
(-3496 3825);
DISPLAY 0.638298 (-3496 3825);
PAINT MONO (-3496 3825);
FORCEPROP 2 LAST CDS_LIB standard
J 0
(-3275 3825);
PAINT MONO (-3275 3825);
DISPLAY INVISIBLE (-3275 3825);
FORCEPROP 1 LAST OFFPAGE TRUE
J 0
(-2950 3700);
DISPLAY 0.872340 (-2950 3700);
DISPLAY INVISIBLE (-2950 3700);
FORCEPROP 1 LAST COMMENT_BODY TRUE
J 0
(-3150 3725);
DISPLAY 0.872340 (-3150 3725);
PAINT GREEN (-3150 3725);
DISPLAY INVISIBLE (-3150 3725);
FORCEPROP 2 LAST PATH I23
J 0
(-3225 3900);
DISPLAY 1.021277 (-3225 3900);
DISPLAY INVISIBLE (-3225 3900);
FORCEADD TAP..1
R 2
(-2350 2050);
FORCEPROP 3 LASTPIN (-2300 2050) SIG_NAME M_D_CPU0_SB_CB<1>
J 0
(-2290 2060);
DISPLAY 0.659574 (-2290 2060);
PAINT MONO (-2290 2060);
DISPLAY INVISIBLE (-2290 2060);
FORCEPROP 1 LASTPIN (-2300 2050) BN 1
J 2
(-2288 2058);
DISPLAY 0.680851 (-2288 2058);
PAINT GREEN (-2288 2058);
FORCEPROP 2 LAST CDS_LIB standard
J 0
(-2350 2050);
DISPLAY INVISIBLE (-2350 2050);
FORCEPROP 1 LAST BODY_TYPE PLUMBING
J 2
(-2350 2100);
DISPLAY 0.872340 (-2350 2100);
PAINT GREEN (-2350 2100);
DISPLAY INVISIBLE (-2350 2100);
FORCEPROP 1 LAST HDL_TAP TRUE
J 2
(-2675 1925);
DISPLAY 0.872340 (-2675 1925);
DISPLAY INVISIBLE (-2675 1925);
FORCEPROP 1 LAST PATH I24
J 2
(-2348 2050);
DISPLAY 0.872340 (-2348 2050);
PAINT GREEN (-2348 2050);
DISPLAY INVISIBLE (-2348 2050);
FORCEADD TAP..1
R 2
(-2350 2100);
FORCEPROP 3 LASTPIN (-2300 2100) SIG_NAME M_D_CPU0_SB_CB<2>
J 0
(-2290 2110);
DISPLAY 0.659574 (-2290 2110);
PAINT MONO (-2290 2110);
DISPLAY INVISIBLE (-2290 2110);
FORCEPROP 1 LASTPIN (-2300 2100) BN 2
J 2
(-2288 2108);
DISPLAY 0.680851 (-2288 2108);
PAINT GREEN (-2288 2108);
FORCEPROP 2 LAST CDS_LIB standard
J 0
(-2350 2100);
DISPLAY INVISIBLE (-2350 2100);
FORCEPROP 1 LAST BODY_TYPE PLUMBING
J 2
(-2350 2150);
DISPLAY 0.872340 (-2350 2150);
PAINT GREEN (-2350 2150);
DISPLAY INVISIBLE (-2350 2150);
FORCEPROP 1 LAST HDL_TAP TRUE
J 2
(-2675 1975);
DISPLAY 0.872340 (-2675 1975);
DISPLAY INVISIBLE (-2675 1975);
FORCEPROP 1 LAST PATH I25
J 2
(-2348 2100);
DISPLAY 0.872340 (-2348 2100);
PAINT GREEN (-2348 2100);
DISPLAY INVISIBLE (-2348 2100);
FORCEADD TAP..1
R 2
(-2350 2150);
FORCEPROP 3 LASTPIN (-2300 2150) SIG_NAME M_D_CPU0_SB_CB<3>
J 0
(-2290 2160);
DISPLAY 0.659574 (-2290 2160);
PAINT MONO (-2290 2160);
DISPLAY INVISIBLE (-2290 2160);
FORCEPROP 1 LASTPIN (-2300 2150) BN 3
J 2
(-2288 2158);
DISPLAY 0.680851 (-2288 2158);
PAINT GREEN (-2288 2158);
FORCEPROP 2 LAST CDS_LIB standard
J 0
(-2350 2150);
DISPLAY INVISIBLE (-2350 2150);
FORCEPROP 1 LAST BODY_TYPE PLUMBING
J 2
(-2350 2200);
DISPLAY 0.872340 (-2350 2200);
PAINT GREEN (-2350 2200);
DISPLAY INVISIBLE (-2350 2200);
FORCEPROP 1 LAST HDL_TAP TRUE
J 2
(-2675 2025);
DISPLAY 0.872340 (-2675 2025);
DISPLAY INVISIBLE (-2675 2025);
FORCEPROP 1 LAST PATH I26
J 2
(-2348 2150);
DISPLAY 0.872340 (-2348 2150);
PAINT GREEN (-2348 2150);
DISPLAY INVISIBLE (-2348 2150);
FORCEADD TAP..1
R 2
(-2350 2200);
FORCEPROP 3 LASTPIN (-2300 2200) SIG_NAME M_D_CPU0_SB_CB<4>
J 0
(-2290 2210);
DISPLAY 0.659574 (-2290 2210);
PAINT MONO (-2290 2210);
DISPLAY INVISIBLE (-2290 2210);
FORCEPROP 1 LASTPIN (-2300 2200) BN 4
J 2
(-2288 2208);
DISPLAY 0.680851 (-2288 2208);
PAINT GREEN (-2288 2208);
FORCEPROP 2 LAST CDS_LIB standard
J 0
(-2350 2200);
DISPLAY INVISIBLE (-2350 2200);
FORCEPROP 1 LAST BODY_TYPE PLUMBING
J 2
(-2350 2250);
DISPLAY 0.872340 (-2350 2250);
PAINT GREEN (-2350 2250);
DISPLAY INVISIBLE (-2350 2250);
FORCEPROP 1 LAST HDL_TAP TRUE
J 2
(-2675 2075);
DISPLAY 0.872340 (-2675 2075);
DISPLAY INVISIBLE (-2675 2075);
FORCEPROP 1 LAST PATH I27
J 2
(-2348 2200);
DISPLAY 0.872340 (-2348 2200);
PAINT GREEN (-2348 2200);
DISPLAY INVISIBLE (-2348 2200);
FORCEADD TAP..1
R 2
(-2350 2250);
FORCEPROP 3 LASTPIN (-2300 2250) SIG_NAME M_D_CPU0_SB_CB<5>
J 0
(-2290 2260);
DISPLAY 0.659574 (-2290 2260);
PAINT MONO (-2290 2260);
DISPLAY INVISIBLE (-2290 2260);
FORCEPROP 1 LASTPIN (-2300 2250) BN 5
J 2
(-2288 2258);
DISPLAY 0.680851 (-2288 2258);
PAINT GREEN (-2288 2258);
FORCEPROP 2 LAST CDS_LIB standard
J 0
(-2350 2250);
DISPLAY INVISIBLE (-2350 2250);
FORCEPROP 1 LAST BODY_TYPE PLUMBING
J 2
(-2350 2300);
DISPLAY 0.872340 (-2350 2300);
PAINT GREEN (-2350 2300);
DISPLAY INVISIBLE (-2350 2300);
FORCEPROP 1 LAST HDL_TAP TRUE
J 2
(-2675 2125);
DISPLAY 0.872340 (-2675 2125);
DISPLAY INVISIBLE (-2675 2125);
FORCEPROP 1 LAST PATH I28
J 2
(-2348 2250);
DISPLAY 0.872340 (-2348 2250);
PAINT GREEN (-2348 2250);
DISPLAY INVISIBLE (-2348 2250);
FORCEADD TAP..1
R 2
(-2350 2300);
FORCEPROP 3 LASTPIN (-2300 2300) SIG_NAME M_D_CPU0_SB_CB<6>
J 0
(-2290 2310);
DISPLAY 0.659574 (-2290 2310);
PAINT MONO (-2290 2310);
DISPLAY INVISIBLE (-2290 2310);
FORCEPROP 1 LASTPIN (-2300 2300) BN 6
J 2
(-2288 2308);
DISPLAY 0.680851 (-2288 2308);
PAINT GREEN (-2288 2308);
FORCEPROP 2 LAST CDS_LIB standard
J 0
(-2350 2300);
DISPLAY INVISIBLE (-2350 2300);
FORCEPROP 1 LAST BODY_TYPE PLUMBING
J 2
(-2350 2350);
DISPLAY 0.872340 (-2350 2350);
PAINT GREEN (-2350 2350);
DISPLAY INVISIBLE (-2350 2350);
FORCEPROP 1 LAST HDL_TAP TRUE
J 2
(-2675 2175);
DISPLAY 0.872340 (-2675 2175);
DISPLAY INVISIBLE (-2675 2175);
FORCEPROP 1 LAST PATH I29
J 2
(-2348 2300);
DISPLAY 0.872340 (-2348 2300);
PAINT GREEN (-2348 2300);
DISPLAY INVISIBLE (-2348 2300);
FORCEADD OFFPAGE..2
R 2
(-3275 250);
FORCEPROP 2 LAST $XR0 89 
J 0
(-3499 250);
DISPLAY 0.638298 (-3499 250);
PAINT MONO (-3499 250);
FORCEPROP 2 LAST CDS_LIB standard
J 0
(-3275 250);
PAINT MONO (-3275 250);
DISPLAY INVISIBLE (-3275 250);
FORCEPROP 1 LAST OFFPAGE TRUE
J 2
(-3600 125);
DISPLAY 0.872340 (-3600 125);
DISPLAY INVISIBLE (-3600 125);
FORCEPROP 1 LAST COMMENT_BODY TRUE
J 2
(-3230 155);
DISPLAY 0.872340 (-3230 155);
PAINT GREEN (-3230 155);
DISPLAY INVISIBLE (-3230 155);
FORCEPROP 2 LAST PATH I3
J 0
(-3225 325);
DISPLAY 1.021277 (-3225 325);
DISPLAY INVISIBLE (-3225 325);
FORCEADD TAP..1
R 2
(-2350 2350);
FORCEPROP 3 LASTPIN (-2300 2350) SIG_NAME M_D_CPU0_SB_CB<7>
J 0
(-2290 2360);
DISPLAY 0.659574 (-2290 2360);
PAINT MONO (-2290 2360);
DISPLAY INVISIBLE (-2290 2360);
FORCEPROP 1 LASTPIN (-2300 2350) BN 7
J 2
(-2288 2358);
DISPLAY 0.680851 (-2288 2358);
PAINT GREEN (-2288 2358);
FORCEPROP 2 LAST CDS_LIB standard
J 0
(-2350 2350);
DISPLAY INVISIBLE (-2350 2350);
FORCEPROP 1 LAST BODY_TYPE PLUMBING
J 2
(-2350 2400);
DISPLAY 0.872340 (-2350 2400);
PAINT GREEN (-2350 2400);
DISPLAY INVISIBLE (-2350 2400);
FORCEPROP 1 LAST HDL_TAP TRUE
J 2
(-2675 2225);
DISPLAY 0.872340 (-2675 2225);
DISPLAY INVISIBLE (-2675 2225);
FORCEPROP 1 LAST PATH I30
J 2
(-2348 2350);
DISPLAY 0.872340 (-2348 2350);
PAINT GREEN (-2348 2350);
DISPLAY INVISIBLE (-2348 2350);
FORCEADD TAP..1
R 2
(-2350 2450);
FORCEPROP 3 LASTPIN (-2300 2450) SIG_NAME M_D_CPU0_SA_CB<0>
J 0
(-2290 2460);
DISPLAY 0.659574 (-2290 2460);
PAINT MONO (-2290 2460);
DISPLAY INVISIBLE (-2290 2460);
FORCEPROP 1 LASTPIN (-2300 2450) BN 0
J 2
(-2288 2458);
DISPLAY 0.680851 (-2288 2458);
PAINT GREEN (-2288 2458);
FORCEPROP 2 LAST CDS_LIB standard
J 0
(-2350 2450);
PAINT MONO (-2350 2450);
DISPLAY INVISIBLE (-2350 2450);
FORCEPROP 1 LAST BODY_TYPE PLUMBING
J 2
(-2350 2500);
DISPLAY 0.872340 (-2350 2500);
PAINT GREEN (-2350 2500);
DISPLAY INVISIBLE (-2350 2500);
FORCEPROP 1 LAST HDL_TAP TRUE
J 2
(-2675 2325);
DISPLAY 0.872340 (-2675 2325);
DISPLAY INVISIBLE (-2675 2325);
FORCEPROP 1 LAST PATH I31
J 2
(-2348 2450);
DISPLAY 0.872340 (-2348 2450);
PAINT GREEN (-2348 2450);
DISPLAY INVISIBLE (-2348 2450);
FORCEADD TAP..1
R 2
(-2350 2500);
FORCEPROP 3 LASTPIN (-2300 2500) SIG_NAME M_D_CPU0_SA_CB<1>
J 0
(-2290 2510);
DISPLAY 0.659574 (-2290 2510);
PAINT MONO (-2290 2510);
DISPLAY INVISIBLE (-2290 2510);
FORCEPROP 1 LASTPIN (-2300 2500) BN 1
J 2
(-2288 2508);
DISPLAY 0.680851 (-2288 2508);
PAINT GREEN (-2288 2508);
FORCEPROP 2 LAST CDS_LIB standard
J 0
(-2350 2500);
DISPLAY INVISIBLE (-2350 2500);
FORCEPROP 1 LAST BODY_TYPE PLUMBING
J 2
(-2350 2550);
DISPLAY 0.872340 (-2350 2550);
PAINT GREEN (-2350 2550);
DISPLAY INVISIBLE (-2350 2550);
FORCEPROP 1 LAST HDL_TAP TRUE
J 2
(-2675 2375);
DISPLAY 0.872340 (-2675 2375);
DISPLAY INVISIBLE (-2675 2375);
FORCEPROP 1 LAST PATH I32
J 2
(-2348 2500);
DISPLAY 0.872340 (-2348 2500);
PAINT GREEN (-2348 2500);
DISPLAY INVISIBLE (-2348 2500);
FORCEADD TAP..1
R 2
(-2350 2550);
FORCEPROP 3 LASTPIN (-2300 2550) SIG_NAME M_D_CPU0_SA_CB<2>
J 0
(-2290 2560);
DISPLAY 0.659574 (-2290 2560);
PAINT MONO (-2290 2560);
DISPLAY INVISIBLE (-2290 2560);
FORCEPROP 1 LASTPIN (-2300 2550) BN 2
J 2
(-2288 2558);
DISPLAY 0.680851 (-2288 2558);
PAINT GREEN (-2288 2558);
FORCEPROP 2 LAST CDS_LIB standard
J 0
(-2350 2550);
DISPLAY INVISIBLE (-2350 2550);
FORCEPROP 1 LAST BODY_TYPE PLUMBING
J 2
(-2350 2600);
DISPLAY 0.872340 (-2350 2600);
PAINT GREEN (-2350 2600);
DISPLAY INVISIBLE (-2350 2600);
FORCEPROP 1 LAST HDL_TAP TRUE
J 2
(-2675 2425);
DISPLAY 0.872340 (-2675 2425);
DISPLAY INVISIBLE (-2675 2425);
FORCEPROP 1 LAST PATH I33
J 2
(-2348 2550);
DISPLAY 0.872340 (-2348 2550);
PAINT GREEN (-2348 2550);
DISPLAY INVISIBLE (-2348 2550);
FORCEADD TAP..1
R 2
(-2350 2600);
FORCEPROP 3 LASTPIN (-2300 2600) SIG_NAME M_D_CPU0_SA_CB<3>
J 0
(-2290 2610);
DISPLAY 0.659574 (-2290 2610);
PAINT MONO (-2290 2610);
DISPLAY INVISIBLE (-2290 2610);
FORCEPROP 1 LASTPIN (-2300 2600) BN 3
J 2
(-2288 2608);
DISPLAY 0.680851 (-2288 2608);
PAINT GREEN (-2288 2608);
FORCEPROP 2 LAST CDS_LIB standard
J 0
(-2350 2600);
DISPLAY INVISIBLE (-2350 2600);
FORCEPROP 1 LAST BODY_TYPE PLUMBING
J 2
(-2350 2650);
DISPLAY 0.872340 (-2350 2650);
PAINT GREEN (-2350 2650);
DISPLAY INVISIBLE (-2350 2650);
FORCEPROP 1 LAST HDL_TAP TRUE
J 2
(-2675 2475);
DISPLAY 0.872340 (-2675 2475);
DISPLAY INVISIBLE (-2675 2475);
FORCEPROP 1 LAST PATH I34
J 2
(-2348 2600);
DISPLAY 0.872340 (-2348 2600);
PAINT GREEN (-2348 2600);
DISPLAY INVISIBLE (-2348 2600);
FORCEADD TAP..1
R 2
(-2350 2650);
FORCEPROP 3 LASTPIN (-2300 2650) SIG_NAME M_D_CPU0_SA_CB<4>
J 0
(-2290 2660);
DISPLAY 0.659574 (-2290 2660);
PAINT MONO (-2290 2660);
DISPLAY INVISIBLE (-2290 2660);
FORCEPROP 1 LASTPIN (-2300 2650) BN 4
J 2
(-2288 2658);
DISPLAY 0.680851 (-2288 2658);
PAINT GREEN (-2288 2658);
FORCEPROP 2 LAST CDS_LIB standard
J 0
(-2350 2650);
DISPLAY INVISIBLE (-2350 2650);
FORCEPROP 1 LAST BODY_TYPE PLUMBING
J 2
(-2350 2700);
DISPLAY 0.872340 (-2350 2700);
PAINT GREEN (-2350 2700);
DISPLAY INVISIBLE (-2350 2700);
FORCEPROP 1 LAST HDL_TAP TRUE
J 2
(-2675 2525);
DISPLAY 0.872340 (-2675 2525);
DISPLAY INVISIBLE (-2675 2525);
FORCEPROP 1 LAST PATH I35
J 2
(-2348 2650);
DISPLAY 0.872340 (-2348 2650);
PAINT GREEN (-2348 2650);
DISPLAY INVISIBLE (-2348 2650);
FORCEADD TAP..1
R 2
(-2350 2700);
FORCEPROP 3 LASTPIN (-2300 2700) SIG_NAME M_D_CPU0_SA_CB<5>
J 0
(-2290 2710);
DISPLAY 0.659574 (-2290 2710);
PAINT MONO (-2290 2710);
DISPLAY INVISIBLE (-2290 2710);
FORCEPROP 1 LASTPIN (-2300 2700) BN 5
J 2
(-2288 2708);
DISPLAY 0.680851 (-2288 2708);
PAINT GREEN (-2288 2708);
FORCEPROP 2 LAST CDS_LIB standard
J 0
(-2350 2700);
DISPLAY INVISIBLE (-2350 2700);
FORCEPROP 1 LAST BODY_TYPE PLUMBING
J 2
(-2350 2750);
DISPLAY 0.872340 (-2350 2750);
PAINT GREEN (-2350 2750);
DISPLAY INVISIBLE (-2350 2750);
FORCEPROP 1 LAST HDL_TAP TRUE
J 2
(-2675 2575);
DISPLAY 0.872340 (-2675 2575);
DISPLAY INVISIBLE (-2675 2575);
FORCEPROP 1 LAST PATH I36
J 2
(-2348 2700);
DISPLAY 0.872340 (-2348 2700);
PAINT GREEN (-2348 2700);
DISPLAY INVISIBLE (-2348 2700);
FORCEADD TAP..1
R 2
(-2350 2750);
FORCEPROP 3 LASTPIN (-2300 2750) SIG_NAME M_D_CPU0_SA_CB<6>
J 0
(-2290 2760);
DISPLAY 0.659574 (-2290 2760);
PAINT MONO (-2290 2760);
DISPLAY INVISIBLE (-2290 2760);
FORCEPROP 1 LASTPIN (-2300 2750) BN 6
J 2
(-2288 2758);
DISPLAY 0.680851 (-2288 2758);
PAINT GREEN (-2288 2758);
FORCEPROP 2 LAST CDS_LIB standard
J 0
(-2350 2750);
DISPLAY INVISIBLE (-2350 2750);
FORCEPROP 1 LAST BODY_TYPE PLUMBING
J 2
(-2350 2800);
DISPLAY 0.872340 (-2350 2800);
PAINT GREEN (-2350 2800);
DISPLAY INVISIBLE (-2350 2800);
FORCEPROP 1 LAST HDL_TAP TRUE
J 2
(-2675 2625);
DISPLAY 0.872340 (-2675 2625);
DISPLAY INVISIBLE (-2675 2625);
FORCEPROP 1 LAST PATH I37
J 2
(-2348 2750);
DISPLAY 0.872340 (-2348 2750);
PAINT GREEN (-2348 2750);
DISPLAY INVISIBLE (-2348 2750);
FORCEADD TAP..1
R 2
(-2350 2800);
FORCEPROP 3 LASTPIN (-2300 2800) SIG_NAME M_D_CPU0_SA_CB<7>
J 0
(-2290 2810);
DISPLAY 0.659574 (-2290 2810);
PAINT MONO (-2290 2810);
DISPLAY INVISIBLE (-2290 2810);
FORCEPROP 1 LASTPIN (-2300 2800) BN 7
J 2
(-2288 2808);
DISPLAY 0.680851 (-2288 2808);
PAINT GREEN (-2288 2808);
FORCEPROP 2 LAST CDS_LIB standard
J 0
(-2350 2800);
DISPLAY INVISIBLE (-2350 2800);
FORCEPROP 1 LAST BODY_TYPE PLUMBING
J 2
(-2350 2850);
DISPLAY 0.872340 (-2350 2850);
PAINT GREEN (-2350 2850);
DISPLAY INVISIBLE (-2350 2850);
FORCEPROP 1 LAST HDL_TAP TRUE
J 2
(-2675 2675);
DISPLAY 0.872340 (-2675 2675);
DISPLAY INVISIBLE (-2675 2675);
FORCEPROP 1 LAST PATH I38
J 2
(-2348 2800);
DISPLAY 0.872340 (-2348 2800);
PAINT GREEN (-2348 2800);
DISPLAY INVISIBLE (-2348 2800);
FORCEADD TAP..1
R 2
(-2350 3500);
FORCEPROP 3 LASTPIN (-2300 3500) SIG_NAME M_D_CPU0_SB_CA<0>
J 0
(-2290 3510);
DISPLAY 0.659574 (-2290 3510);
PAINT MONO (-2290 3510);
DISPLAY INVISIBLE (-2290 3510);
FORCEPROP 1 LASTPIN (-2300 3500) BN 0
J 2
(-2288 3508);
DISPLAY 0.680851 (-2288 3508);
PAINT GREEN (-2288 3508);
FORCEPROP 2 LAST CDS_LIB standard
J 0
(-2350 3500);
DISPLAY INVISIBLE (-2350 3500);
FORCEPROP 1 LAST BODY_TYPE PLUMBING
J 2
(-2350 3550);
DISPLAY 0.872340 (-2350 3550);
PAINT GREEN (-2350 3550);
DISPLAY INVISIBLE (-2350 3550);
FORCEPROP 1 LAST HDL_TAP TRUE
J 2
(-2675 3375);
DISPLAY 0.872340 (-2675 3375);
DISPLAY INVISIBLE (-2675 3375);
FORCEPROP 1 LAST PATH I39
J 2
(-2348 3500);
DISPLAY 0.872340 (-2348 3500);
PAINT GREEN (-2348 3500);
DISPLAY INVISIBLE (-2348 3500);
FORCEADD OFFPAGE..2
R 2
(-3275 750);
FORCEPROP 2 LAST $XR0 23 
J 0
(-3499 750);
DISPLAY 0.638298 (-3499 750);
PAINT MONO (-3499 750);
FORCEPROP 2 LAST CDS_LIB standard
J 0
(-3275 750);
PAINT MONO (-3275 750);
DISPLAY INVISIBLE (-3275 750);
FORCEPROP 1 LAST OFFPAGE TRUE
J 2
(-3600 625);
DISPLAY 0.872340 (-3600 625);
DISPLAY INVISIBLE (-3600 625);
FORCEPROP 1 LAST COMMENT_BODY TRUE
J 2
(-3230 655);
DISPLAY 0.872340 (-3230 655);
PAINT GREEN (-3230 655);
DISPLAY INVISIBLE (-3230 655);
FORCEPROP 2 LAST PATH I4
J 0
(-3225 825);
DISPLAY 1.021277 (-3225 825);
DISPLAY INVISIBLE (-3225 825);
FORCEADD TAP..1
R 2
(-2350 3550);
FORCEPROP 3 LASTPIN (-2300 3550) SIG_NAME M_D_CPU0_SB_CA<1>
J 0
(-2290 3560);
DISPLAY 0.659574 (-2290 3560);
PAINT MONO (-2290 3560);
DISPLAY INVISIBLE (-2290 3560);
FORCEPROP 1 LASTPIN (-2300 3550) BN 1
J 2
(-2288 3558);
DISPLAY 0.680851 (-2288 3558);
PAINT GREEN (-2288 3558);
FORCEPROP 2 LAST CDS_LIB standard
J 0
(-2350 3550);
DISPLAY INVISIBLE (-2350 3550);
FORCEPROP 1 LAST BODY_TYPE PLUMBING
J 2
(-2350 3600);
DISPLAY 0.872340 (-2350 3600);
PAINT GREEN (-2350 3600);
DISPLAY INVISIBLE (-2350 3600);
FORCEPROP 1 LAST HDL_TAP TRUE
J 2
(-2675 3425);
DISPLAY 0.872340 (-2675 3425);
DISPLAY INVISIBLE (-2675 3425);
FORCEPROP 1 LAST PATH I40
J 2
(-2348 3550);
DISPLAY 0.872340 (-2348 3550);
PAINT GREEN (-2348 3550);
DISPLAY INVISIBLE (-2348 3550);
FORCEADD TAP..1
R 2
(-2350 3600);
FORCEPROP 3 LASTPIN (-2300 3600) SIG_NAME M_D_CPU0_SB_CA<2>
J 0
(-2290 3610);
DISPLAY 0.659574 (-2290 3610);
PAINT MONO (-2290 3610);
DISPLAY INVISIBLE (-2290 3610);
FORCEPROP 1 LASTPIN (-2300 3600) BN 2
J 2
(-2288 3608);
DISPLAY 0.680851 (-2288 3608);
PAINT GREEN (-2288 3608);
FORCEPROP 2 LAST CDS_LIB standard
J 0
(-2350 3600);
DISPLAY INVISIBLE (-2350 3600);
FORCEPROP 1 LAST BODY_TYPE PLUMBING
J 2
(-2350 3650);
DISPLAY 0.872340 (-2350 3650);
PAINT GREEN (-2350 3650);
DISPLAY INVISIBLE (-2350 3650);
FORCEPROP 1 LAST HDL_TAP TRUE
J 2
(-2675 3475);
DISPLAY 0.872340 (-2675 3475);
DISPLAY INVISIBLE (-2675 3475);
FORCEPROP 1 LAST PATH I41
J 2
(-2348 3600);
DISPLAY 0.872340 (-2348 3600);
PAINT GREEN (-2348 3600);
DISPLAY INVISIBLE (-2348 3600);
FORCEADD TAP..1
R 2
(-2350 3650);
FORCEPROP 3 LASTPIN (-2300 3650) SIG_NAME M_D_CPU0_SB_CA<3>
J 0
(-2290 3660);
DISPLAY 0.659574 (-2290 3660);
PAINT MONO (-2290 3660);
DISPLAY INVISIBLE (-2290 3660);
FORCEPROP 1 LASTPIN (-2300 3650) BN 3
J 2
(-2288 3658);
DISPLAY 0.680851 (-2288 3658);
PAINT GREEN (-2288 3658);
FORCEPROP 2 LAST CDS_LIB standard
J 0
(-2350 3650);
DISPLAY INVISIBLE (-2350 3650);
FORCEPROP 1 LAST BODY_TYPE PLUMBING
J 2
(-2350 3700);
DISPLAY 0.872340 (-2350 3700);
PAINT GREEN (-2350 3700);
DISPLAY INVISIBLE (-2350 3700);
FORCEPROP 1 LAST HDL_TAP TRUE
J 2
(-2675 3525);
DISPLAY 0.872340 (-2675 3525);
DISPLAY INVISIBLE (-2675 3525);
FORCEPROP 1 LAST PATH I42
J 2
(-2348 3650);
DISPLAY 0.872340 (-2348 3650);
PAINT GREEN (-2348 3650);
DISPLAY INVISIBLE (-2348 3650);
FORCEADD TAP..1
R 2
(-2350 3700);
FORCEPROP 3 LASTPIN (-2300 3700) SIG_NAME M_D_CPU0_SB_CA<4>
J 0
(-2290 3710);
DISPLAY 0.659574 (-2290 3710);
PAINT MONO (-2290 3710);
DISPLAY INVISIBLE (-2290 3710);
FORCEPROP 1 LASTPIN (-2300 3700) BN 4
J 2
(-2288 3708);
DISPLAY 0.680851 (-2288 3708);
PAINT GREEN (-2288 3708);
FORCEPROP 2 LAST CDS_LIB standard
J 0
(-2350 3700);
DISPLAY INVISIBLE (-2350 3700);
FORCEPROP 1 LAST BODY_TYPE PLUMBING
J 2
(-2350 3750);
DISPLAY 0.872340 (-2350 3750);
PAINT GREEN (-2350 3750);
DISPLAY INVISIBLE (-2350 3750);
FORCEPROP 1 LAST HDL_TAP TRUE
J 2
(-2675 3575);
DISPLAY 0.872340 (-2675 3575);
DISPLAY INVISIBLE (-2675 3575);
FORCEPROP 1 LAST PATH I43
J 2
(-2348 3700);
DISPLAY 0.872340 (-2348 3700);
PAINT GREEN (-2348 3700);
DISPLAY INVISIBLE (-2348 3700);
FORCEADD TAP..1
R 2
(-2350 3800);
FORCEPROP 3 LASTPIN (-2300 3800) SIG_NAME M_D_CPU0_SB_CA<6>
J 0
(-2290 3810);
DISPLAY 0.659574 (-2290 3810);
PAINT MONO (-2290 3810);
DISPLAY INVISIBLE (-2290 3810);
FORCEPROP 1 LASTPIN (-2300 3800) BN 6
J 2
(-2288 3808);
DISPLAY 0.680851 (-2288 3808);
PAINT GREEN (-2288 3808);
FORCEPROP 2 LAST CDS_LIB standard
J 0
(-2350 3800);
DISPLAY INVISIBLE (-2350 3800);
FORCEPROP 1 LAST BODY_TYPE PLUMBING
J 2
(-2350 3850);
DISPLAY 0.872340 (-2350 3850);
PAINT GREEN (-2350 3850);
DISPLAY INVISIBLE (-2350 3850);
FORCEPROP 1 LAST HDL_TAP TRUE
J 2
(-2675 3675);
DISPLAY 0.872340 (-2675 3675);
DISPLAY INVISIBLE (-2675 3675);
FORCEPROP 1 LAST PATH I44
J 2
(-2348 3800);
DISPLAY 0.872340 (-2348 3800);
PAINT GREEN (-2348 3800);
DISPLAY INVISIBLE (-2348 3800);
FORCEADD TAP..1
R 2
(-2350 3750);
FORCEPROP 3 LASTPIN (-2300 3750) SIG_NAME M_D_CPU0_SB_CA<5>
J 0
(-2290 3760);
DISPLAY 0.659574 (-2290 3760);
PAINT MONO (-2290 3760);
DISPLAY INVISIBLE (-2290 3760);
FORCEPROP 1 LASTPIN (-2300 3750) BN 5
J 2
(-2288 3758);
DISPLAY 0.680851 (-2288 3758);
PAINT GREEN (-2288 3758);
FORCEPROP 2 LAST CDS_LIB standard
J 0
(-2350 3750);
DISPLAY INVISIBLE (-2350 3750);
FORCEPROP 1 LAST BODY_TYPE PLUMBING
J 2
(-2350 3800);
DISPLAY 0.872340 (-2350 3800);
PAINT GREEN (-2350 3800);
DISPLAY INVISIBLE (-2350 3800);
FORCEPROP 1 LAST HDL_TAP TRUE
J 2
(-2675 3625);
DISPLAY 0.872340 (-2675 3625);
DISPLAY INVISIBLE (-2675 3625);
FORCEPROP 1 LAST PATH I45
J 2
(-2348 3750);
DISPLAY 0.872340 (-2348 3750);
PAINT GREEN (-2348 3750);
DISPLAY INVISIBLE (-2348 3750);
FORCEADD TAP..1
R 2
(-2350 3900);
FORCEPROP 3 LASTPIN (-2300 3900) SIG_NAME M_D_CPU0_SA_CA<0>
J 0
(-2290 3910);
DISPLAY 0.659574 (-2290 3910);
PAINT MONO (-2290 3910);
DISPLAY INVISIBLE (-2290 3910);
FORCEPROP 1 LASTPIN (-2300 3900) BN 0
J 2
(-2288 3908);
DISPLAY 0.680851 (-2288 3908);
PAINT GREEN (-2288 3908);
FORCEPROP 2 LAST CDS_LIB standard
J 0
(-2350 3900);
DISPLAY INVISIBLE (-2350 3900);
FORCEPROP 1 LAST BODY_TYPE PLUMBING
J 2
(-2350 3950);
DISPLAY 0.872340 (-2350 3950);
PAINT GREEN (-2350 3950);
DISPLAY INVISIBLE (-2350 3950);
FORCEPROP 1 LAST HDL_TAP TRUE
J 2
(-2675 3775);
DISPLAY 0.872340 (-2675 3775);
DISPLAY INVISIBLE (-2675 3775);
FORCEPROP 1 LAST PATH I46
J 2
(-2348 3900);
DISPLAY 0.872340 (-2348 3900);
PAINT GREEN (-2348 3900);
DISPLAY INVISIBLE (-2348 3900);
FORCEADD TAP..1
R 2
(-2350 3950);
FORCEPROP 3 LASTPIN (-2300 3950) SIG_NAME M_D_CPU0_SA_CA<1>
J 0
(-2290 3960);
DISPLAY 0.659574 (-2290 3960);
PAINT MONO (-2290 3960);
DISPLAY INVISIBLE (-2290 3960);
FORCEPROP 1 LASTPIN (-2300 3950) BN 1
J 2
(-2288 3958);
DISPLAY 0.680851 (-2288 3958);
PAINT GREEN (-2288 3958);
FORCEPROP 2 LAST CDS_LIB standard
J 0
(-2350 3950);
DISPLAY INVISIBLE (-2350 3950);
FORCEPROP 1 LAST BODY_TYPE PLUMBING
J 2
(-2350 4000);
DISPLAY 0.872340 (-2350 4000);
PAINT GREEN (-2350 4000);
DISPLAY INVISIBLE (-2350 4000);
FORCEPROP 1 LAST HDL_TAP TRUE
J 2
(-2675 3825);
DISPLAY 0.872340 (-2675 3825);
DISPLAY INVISIBLE (-2675 3825);
FORCEPROP 1 LAST PATH I47
J 2
(-2348 3950);
DISPLAY 0.872340 (-2348 3950);
PAINT GREEN (-2348 3950);
DISPLAY INVISIBLE (-2348 3950);
FORCEADD TAP..1
R 2
(-2350 4050);
FORCEPROP 3 LASTPIN (-2300 4050) SIG_NAME M_D_CPU0_SA_CA<3>
J 0
(-2290 4060);
DISPLAY 0.659574 (-2290 4060);
PAINT MONO (-2290 4060);
DISPLAY INVISIBLE (-2290 4060);
FORCEPROP 1 LASTPIN (-2300 4050) BN 3
J 2
(-2288 4058);
DISPLAY 0.680851 (-2288 4058);
PAINT GREEN (-2288 4058);
FORCEPROP 2 LAST CDS_LIB standard
J 0
(-2350 4050);
DISPLAY INVISIBLE (-2350 4050);
FORCEPROP 1 LAST BODY_TYPE PLUMBING
J 2
(-2350 4100);
DISPLAY 0.872340 (-2350 4100);
PAINT GREEN (-2350 4100);
DISPLAY INVISIBLE (-2350 4100);
FORCEPROP 1 LAST HDL_TAP TRUE
J 2
(-2675 3925);
DISPLAY 0.872340 (-2675 3925);
DISPLAY INVISIBLE (-2675 3925);
FORCEPROP 1 LAST PATH I48
J 2
(-2348 4050);
DISPLAY 0.872340 (-2348 4050);
PAINT GREEN (-2348 4050);
DISPLAY INVISIBLE (-2348 4050);
FORCEADD TAP..1
R 2
(-2350 4000);
FORCEPROP 3 LASTPIN (-2300 4000) SIG_NAME M_D_CPU0_SA_CA<2>
J 0
(-2290 4010);
DISPLAY 0.659574 (-2290 4010);
PAINT MONO (-2290 4010);
DISPLAY INVISIBLE (-2290 4010);
FORCEPROP 1 LASTPIN (-2300 4000) BN 2
J 2
(-2288 4008);
DISPLAY 0.680851 (-2288 4008);
PAINT GREEN (-2288 4008);
FORCEPROP 2 LAST CDS_LIB standard
J 0
(-2350 4000);
DISPLAY INVISIBLE (-2350 4000);
FORCEPROP 1 LAST BODY_TYPE PLUMBING
J 2
(-2350 4050);
DISPLAY 0.872340 (-2350 4050);
PAINT GREEN (-2350 4050);
DISPLAY INVISIBLE (-2350 4050);
FORCEPROP 1 LAST HDL_TAP TRUE
J 2
(-2675 3875);
DISPLAY 0.872340 (-2675 3875);
DISPLAY INVISIBLE (-2675 3875);
FORCEPROP 1 LAST PATH I49
J 2
(-2348 4000);
DISPLAY 0.872340 (-2348 4000);
PAINT GREEN (-2348 4000);
DISPLAY INVISIBLE (-2348 4000);
FORCEADD OFFPAGE..2
R 2
(-3275 800);
FORCEPROP 2 LAST $XR0 23 
J 0
(-3499 800);
DISPLAY 0.638298 (-3499 800);
PAINT MONO (-3499 800);
FORCEPROP 2 LAST CDS_LIB standard
J 0
(-3275 800);
PAINT MONO (-3275 800);
DISPLAY INVISIBLE (-3275 800);
FORCEPROP 1 LAST OFFPAGE TRUE
J 2
(-3600 675);
DISPLAY 0.872340 (-3600 675);
DISPLAY INVISIBLE (-3600 675);
FORCEPROP 1 LAST COMMENT_BODY TRUE
J 2
(-3230 705);
DISPLAY 0.872340 (-3230 705);
PAINT GREEN (-3230 705);
DISPLAY INVISIBLE (-3230 705);
FORCEPROP 2 LAST PATH I5
J 0
(-3225 875);
DISPLAY 1.021277 (-3225 875);
DISPLAY INVISIBLE (-3225 875);
FORCEADD SCONN288_ADR50017P087CC..1
(-1525 2475);
FORCEPROP 1 LAST PART_NUMBER DFHST8FS460
J 0
(-1970 4485);
DISPLAY 0.723404 (-1970 4485);
PAINT GREEN (-1970 4485);
DISPLAY INVISIBLE (-1970 4485);
FORCEPROP 1 LAST MATERIAL IO
J 0
(-1970 4358);
DISPLAY 0.723404 (-1970 4358);
PAINT GREEN (-1970 4358);
FORCEPROP 2 LAST PART_TYPE SMLF
J 0
(-1975 4650);
DISPLAY 1.021277 (-1975 4650);
FORCEPROP 2 LAST VALUE SCONN288_ADR50017-P087CC
J 0
(-1975 4600);
DISPLAY 1.021277 (-1975 4600);
FORCEPROP 1 LAST $LOCATION J8
J 0
(-1975 4550);
DISPLAY 0.723404 (-1975 4550);
PAINT GREEN (-1975 4550);
FORCEPROP 0 LASTPIN (-2125 1850) $PN 62
J 2
(-2135 1860);
DISPLAY 0.680851 (-2135 1860);
PAINT MONO (-2135 1860);
FORCEPROP 0 LASTPIN (-2125 3900) $PN 66
J 2
(-2135 3910);
DISPLAY 0.680851 (-2135 3910);
PAINT MONO (-2135 3910);
FORCEPROP 0 LASTPIN (-2125 3500) $PN 76
J 2
(-2135 3510);
DISPLAY 0.680851 (-2135 3510);
PAINT MONO (-2135 3510);
FORCEPROP 0 LASTPIN (-2125 3950) $PN 211
J 2
(-2135 3960);
DISPLAY 0.680851 (-2135 3960);
PAINT MONO (-2135 3960);
FORCEPROP 0 LASTPIN (-2125 3550) $PN 221
J 2
(-2135 3560);
DISPLAY 0.680851 (-2135 3560);
PAINT MONO (-2135 3560);
FORCEPROP 0 LASTPIN (-2125 4000) $PN 68
J 2
(-2135 4010);
DISPLAY 0.680851 (-2135 4010);
PAINT MONO (-2135 4010);
FORCEPROP 0 LASTPIN (-2125 3600) $PN 78
J 2
(-2135 3610);
DISPLAY 0.680851 (-2135 3610);
PAINT MONO (-2135 3610);
FORCEPROP 0 LASTPIN (-2125 4050) $PN 213
J 2
(-2135 4060);
DISPLAY 0.680851 (-2135 4060);
PAINT MONO (-2135 4060);
FORCEPROP 0 LASTPIN (-2125 3650) $PN 223
J 2
(-2135 3660);
DISPLAY 0.680851 (-2135 3660);
PAINT MONO (-2135 3660);
FORCEPROP 0 LASTPIN (-2125 4100) $PN 70
J 2
(-2135 4110);
DISPLAY 0.680851 (-2135 4110);
PAINT MONO (-2135 4110);
FORCEPROP 0 LASTPIN (-2125 3700) $PN 80
J 2
(-2135 3710);
DISPLAY 0.680851 (-2135 3710);
PAINT MONO (-2135 3710);
FORCEPROP 0 LASTPIN (-2125 4150) $PN 215
J 2
(-2135 4160);
DISPLAY 0.680851 (-2135 4160);
PAINT MONO (-2135 4160);
FORCEPROP 0 LASTPIN (-2125 3750) $PN 225
J 2
(-2135 3760);
DISPLAY 0.680851 (-2135 3760);
PAINT MONO (-2135 3760);
FORCEPROP 0 LASTPIN (-2125 4200) $PN 72
J 2
(-2135 4210);
DISPLAY 0.680851 (-2135 4210);
PAINT MONO (-2135 4210);
FORCEPROP 0 LASTPIN (-2125 3800) $PN 82
J 2
(-2135 3810);
DISPLAY 0.680851 (-2135 3810);
PAINT MONO (-2135 3810);
FORCEPROP 0 LASTPIN (-2125 2450) $PN 51
J 2
(-2135 2460);
DISPLAY 0.680851 (-2135 2460);
PAINT MONO (-2135 2460);
FORCEPROP 0 LASTPIN (-2125 2000) $PN 96
J 2
(-2135 2010);
DISPLAY 0.680851 (-2135 2010);
PAINT MONO (-2135 2010);
FORCEPROP 0 LASTPIN (-2125 2500) $PN 53
J 2
(-2135 2510);
DISPLAY 0.680851 (-2135 2510);
PAINT MONO (-2135 2510);
FORCEPROP 0 LASTPIN (-2125 2050) $PN 98
J 2
(-2135 2060);
DISPLAY 0.680851 (-2135 2060);
PAINT MONO (-2135 2060);
FORCEPROP 0 LASTPIN (-2125 2550) $PN 196
J 2
(-2135 2560);
DISPLAY 0.680851 (-2135 2560);
PAINT MONO (-2135 2560);
FORCEPROP 0 LASTPIN (-2125 2100) $PN 241
J 2
(-2135 2110);
DISPLAY 0.680851 (-2135 2110);
PAINT MONO (-2135 2110);
FORCEPROP 0 LASTPIN (-2125 2600) $PN 198
J 2
(-2135 2610);
DISPLAY 0.680851 (-2135 2610);
PAINT MONO (-2135 2610);
FORCEPROP 0 LASTPIN (-2125 2150) $PN 243
J 2
(-2135 2160);
DISPLAY 0.680851 (-2135 2160);
PAINT MONO (-2135 2160);
FORCEPROP 0 LASTPIN (-2125 2650) $PN 58
J 2
(-2135 2660);
DISPLAY 0.680851 (-2135 2660);
PAINT MONO (-2135 2660);
FORCEPROP 0 LASTPIN (-2125 2200) $PN 89
J 2
(-2135 2210);
DISPLAY 0.680851 (-2135 2210);
PAINT MONO (-2135 2210);
FORCEPROP 0 LASTPIN (-2125 2700) $PN 60
J 2
(-2135 2710);
DISPLAY 0.680851 (-2135 2710);
PAINT MONO (-2135 2710);
FORCEPROP 0 LASTPIN (-2125 2250) $PN 91
J 2
(-2135 2260);
DISPLAY 0.680851 (-2135 2260);
PAINT MONO (-2135 2260);
FORCEPROP 0 LASTPIN (-2125 2750) $PN 203
J 2
(-2135 2760);
DISPLAY 0.680851 (-2135 2760);
PAINT MONO (-2135 2760);
FORCEPROP 0 LASTPIN (-2125 2300) $PN 234
J 2
(-2135 2310);
DISPLAY 0.680851 (-2135 2310);
PAINT MONO (-2135 2310);
FORCEPROP 0 LASTPIN (-2125 2800) $PN 205
J 2
(-2135 2810);
DISPLAY 0.680851 (-2135 2810);
PAINT MONO (-2135 2810);
FORCEPROP 0 LASTPIN (-2125 2350) $PN 236
J 2
(-2135 2360);
DISPLAY 0.680851 (-2135 2360);
PAINT MONO (-2135 2360);
FORCEPROP 0 LASTPIN (-2125 2900) $PN 218
J 2
(-2135 2910);
DISPLAY 0.680851 (-2135 2910);
PAINT MONO (-2135 2910);
FORCEPROP 0 LASTPIN (-2125 2950) $PN 217
J 2
(-2135 2960);
DISPLAY 0.680851 (-2135 2960);
PAINT MONO (-2135 2960);
FORCEPROP 0 LASTPIN (-2125 3200) $PN 64
J 2
(-2135 3210);
DISPLAY 0.680851 (-2135 3210);
PAINT MONO (-2135 3210);
FORCEPROP 0 LASTPIN (-2125 3050) $PN 84
J 2
(-2135 3060);
DISPLAY 0.680851 (-2135 3060);
PAINT MONO (-2135 3060);
FORCEPROP 0 LASTPIN (-2125 3250) $PN 209
J 2
(-2135 3260);
DISPLAY 0.680851 (-2135 3260);
PAINT MONO (-2135 3260);
FORCEPROP 0 LASTPIN (-2125 3100) $PN 229
J 2
(-2135 3110);
DISPLAY 0.680851 (-2135 3110);
PAINT MONO (-2135 3110);
FORCEPROP 0 LASTPIN (-925 2650) $PN 7
J 0
(-915 2660);
DISPLAY 0.680851 (-915 2660);
PAINT MONO (-915 2660);
FORCEPROP 0 LASTPIN (-925 1000) $PN 100
J 0
(-915 1010);
DISPLAY 0.680851 (-915 1010);
PAINT MONO (-915 1010);
FORCEPROP 0 LASTPIN (-925 2700) $PN 9
J 0
(-915 2710);
DISPLAY 0.680851 (-915 2710);
PAINT MONO (-915 2710);
FORCEPROP 0 LASTPIN (-925 1050) $PN 102
J 0
(-915 1060);
DISPLAY 0.680851 (-915 1060);
PAINT MONO (-915 1060);
FORCEPROP 0 LASTPIN (-925 2750) $PN 152
J 0
(-915 2760);
DISPLAY 0.680851 (-915 2760);
PAINT MONO (-915 2760);
FORCEPROP 0 LASTPIN (-925 1100) $PN 245
J 0
(-915 1110);
DISPLAY 0.680851 (-915 1110);
PAINT MONO (-915 1110);
FORCEPROP 0 LASTPIN (-925 2800) $PN 154
J 0
(-915 2810);
DISPLAY 0.680851 (-915 2810);
PAINT MONO (-915 2810);
FORCEPROP 0 LASTPIN (-925 1150) $PN 247
J 0
(-915 1160);
DISPLAY 0.680851 (-915 1160);
PAINT MONO (-915 1160);
FORCEPROP 0 LASTPIN (-925 2850) $PN 14
J 0
(-915 2860);
DISPLAY 0.680851 (-915 2860);
PAINT MONO (-915 2860);
FORCEPROP 0 LASTPIN (-925 1200) $PN 107
J 0
(-915 1210);
DISPLAY 0.680851 (-915 1210);
PAINT MONO (-915 1210);
FORCEPROP 0 LASTPIN (-925 2900) $PN 16
J 0
(-915 2910);
DISPLAY 0.680851 (-915 2910);
PAINT MONO (-915 2910);
FORCEPROP 0 LASTPIN (-925 1250) $PN 109
J 0
(-915 1260);
DISPLAY 0.680851 (-915 1260);
PAINT MONO (-915 1260);
FORCEPROP 0 LASTPIN (-925 2950) $PN 159
J 0
(-915 2960);
DISPLAY 0.680851 (-915 2960);
PAINT MONO (-915 2960);
FORCEPROP 0 LASTPIN (-925 1300) $PN 252
J 0
(-915 1310);
DISPLAY 0.680851 (-915 1310);
PAINT MONO (-915 1310);
FORCEPROP 0 LASTPIN (-925 3000) $PN 161
J 0
(-915 3010);
DISPLAY 0.680851 (-915 3010);
PAINT MONO (-915 3010);
FORCEPROP 0 LASTPIN (-925 1350) $PN 254
J 0
(-915 1360);
DISPLAY 0.680851 (-915 1360);
PAINT MONO (-915 1360);
FORCEPROP 0 LASTPIN (-925 3050) $PN 18
J 0
(-915 3060);
DISPLAY 0.680851 (-915 3060);
PAINT MONO (-915 3060);
FORCEPROP 0 LASTPIN (-925 1400) $PN 111
J 0
(-915 1410);
DISPLAY 0.680851 (-915 1410);
PAINT MONO (-915 1410);
FORCEPROP 0 LASTPIN (-925 3100) $PN 20
J 0
(-915 3110);
DISPLAY 0.680851 (-915 3110);
PAINT MONO (-915 3110);
FORCEPROP 0 LASTPIN (-925 1450) $PN 113
J 0
(-915 1460);
DISPLAY 0.680851 (-915 1460);
PAINT MONO (-915 1460);
FORCEPROP 0 LASTPIN (-925 3150) $PN 163
J 0
(-915 3160);
DISPLAY 0.680851 (-915 3160);
PAINT MONO (-915 3160);
FORCEPROP 0 LASTPIN (-925 1500) $PN 256
J 0
(-915 1510);
DISPLAY 0.680851 (-915 1510);
PAINT MONO (-915 1510);
FORCEPROP 0 LASTPIN (-925 3200) $PN 165
J 0
(-915 3210);
DISPLAY 0.680851 (-915 3210);
PAINT MONO (-915 3210);
FORCEPROP 0 LASTPIN (-925 1550) $PN 258
J 0
(-915 1560);
DISPLAY 0.680851 (-915 1560);
PAINT MONO (-915 1560);
FORCEPROP 0 LASTPIN (-925 3250) $PN 25
J 0
(-915 3260);
DISPLAY 0.680851 (-915 3260);
PAINT MONO (-915 3260);
FORCEPROP 0 LASTPIN (-925 1600) $PN 118
J 0
(-915 1610);
DISPLAY 0.680851 (-915 1610);
PAINT MONO (-915 1610);
FORCEPROP 0 LASTPIN (-925 3300) $PN 27
J 0
(-915 3310);
DISPLAY 0.680851 (-915 3310);
PAINT MONO (-915 3310);
FORCEPROP 0 LASTPIN (-925 1650) $PN 120
J 0
(-915 1660);
DISPLAY 0.680851 (-915 1660);
PAINT MONO (-915 1660);
FORCEPROP 0 LASTPIN (-925 3350) $PN 170
J 0
(-915 3360);
DISPLAY 0.680851 (-915 3360);
PAINT MONO (-915 3360);
FORCEPROP 0 LASTPIN (-925 1700) $PN 263
J 0
(-915 1710);
DISPLAY 0.680851 (-915 1710);
PAINT MONO (-915 1710);
FORCEPROP 0 LASTPIN (-925 3400) $PN 172
J 0
(-915 3410);
DISPLAY 0.680851 (-915 3410);
PAINT MONO (-915 3410);
FORCEPROP 0 LASTPIN (-925 1750) $PN 265
J 0
(-915 1760);
DISPLAY 0.680851 (-915 1760);
PAINT MONO (-915 1760);
FORCEPROP 0 LASTPIN (-925 3450) $PN 29
J 0
(-915 3460);
DISPLAY 0.680851 (-915 3460);
PAINT MONO (-915 3460);
FORCEPROP 0 LASTPIN (-925 1800) $PN 122
J 0
(-915 1810);
DISPLAY 0.680851 (-915 1810);
PAINT MONO (-915 1810);
FORCEPROP 0 LASTPIN (-925 3500) $PN 31
J 0
(-915 3510);
DISPLAY 0.680851 (-915 3510);
PAINT MONO (-915 3510);
FORCEPROP 0 LASTPIN (-925 1850) $PN 124
J 0
(-915 1860);
DISPLAY 0.680851 (-915 1860);
PAINT MONO (-915 1860);
FORCEPROP 0 LASTPIN (-925 3550) $PN 174
J 0
(-915 3560);
DISPLAY 0.680851 (-915 3560);
PAINT MONO (-915 3560);
FORCEPROP 0 LASTPIN (-925 1900) $PN 267
J 0
(-915 1910);
DISPLAY 0.680851 (-915 1910);
PAINT MONO (-915 1910);
FORCEPROP 0 LASTPIN (-925 3600) $PN 176
J 0
(-915 3610);
DISPLAY 0.680851 (-915 3610);
PAINT MONO (-915 3610);
FORCEPROP 0 LASTPIN (-925 1950) $PN 269
J 0
(-915 1960);
DISPLAY 0.680851 (-915 1960);
PAINT MONO (-915 1960);
FORCEPROP 0 LASTPIN (-925 3650) $PN 36
J 0
(-915 3660);
DISPLAY 0.680851 (-915 3660);
PAINT MONO (-915 3660);
FORCEPROP 0 LASTPIN (-925 2000) $PN 129
J 0
(-915 2010);
DISPLAY 0.680851 (-915 2010);
PAINT MONO (-915 2010);
FORCEPROP 0 LASTPIN (-925 3700) $PN 38
J 0
(-915 3710);
DISPLAY 0.680851 (-915 3710);
PAINT MONO (-915 3710);
FORCEPROP 0 LASTPIN (-925 2050) $PN 131
J 0
(-915 2060);
DISPLAY 0.680851 (-915 2060);
PAINT MONO (-915 2060);
FORCEPROP 0 LASTPIN (-925 3750) $PN 181
J 0
(-915 3760);
DISPLAY 0.680851 (-915 3760);
PAINT MONO (-915 3760);
FORCEPROP 0 LASTPIN (-925 2100) $PN 274
J 0
(-915 2110);
DISPLAY 0.680851 (-915 2110);
PAINT MONO (-915 2110);
FORCEPROP 0 LASTPIN (-925 3800) $PN 183
J 0
(-915 3810);
DISPLAY 0.680851 (-915 3810);
PAINT MONO (-915 3810);
FORCEPROP 0 LASTPIN (-925 2150) $PN 276
J 0
(-915 2160);
DISPLAY 0.680851 (-915 2160);
PAINT MONO (-915 2160);
FORCEPROP 0 LASTPIN (-925 3850) $PN 40
J 0
(-915 3860);
DISPLAY 0.680851 (-915 3860);
PAINT MONO (-915 3860);
FORCEPROP 0 LASTPIN (-925 2200) $PN 133
J 0
(-915 2210);
DISPLAY 0.680851 (-915 2210);
PAINT MONO (-915 2210);
FORCEPROP 0 LASTPIN (-925 3900) $PN 42
J 0
(-915 3910);
DISPLAY 0.680851 (-915 3910);
PAINT MONO (-915 3910);
FORCEPROP 0 LASTPIN (-925 2250) $PN 135
J 0
(-915 2260);
DISPLAY 0.680851 (-915 2260);
PAINT MONO (-915 2260);
FORCEPROP 0 LASTPIN (-925 3950) $PN 185
J 0
(-915 3960);
DISPLAY 0.680851 (-915 3960);
PAINT MONO (-915 3960);
FORCEPROP 0 LASTPIN (-925 2300) $PN 278
J 0
(-915 2310);
DISPLAY 0.680851 (-915 2310);
PAINT MONO (-915 2310);
FORCEPROP 0 LASTPIN (-925 4000) $PN 187
J 0
(-915 4010);
DISPLAY 0.680851 (-915 4010);
PAINT MONO (-915 4010);
FORCEPROP 0 LASTPIN (-925 2350) $PN 280
J 0
(-915 2360);
DISPLAY 0.680851 (-915 2360);
PAINT MONO (-915 2360);
FORCEPROP 0 LASTPIN (-925 4050) $PN 47
J 0
(-915 4060);
DISPLAY 0.680851 (-915 4060);
PAINT MONO (-915 4060);
FORCEPROP 0 LASTPIN (-925 2400) $PN 140
J 0
(-915 2410);
DISPLAY 0.680851 (-915 2410);
PAINT MONO (-915 2410);
FORCEPROP 0 LASTPIN (-925 4100) $PN 49
J 0
(-915 4110);
DISPLAY 0.680851 (-915 4110);
PAINT MONO (-915 4110);
FORCEPROP 0 LASTPIN (-925 2450) $PN 142
J 0
(-915 2460);
DISPLAY 0.680851 (-915 2460);
PAINT MONO (-915 2460);
FORCEPROP 0 LASTPIN (-925 4150) $PN 192
J 0
(-915 4160);
DISPLAY 0.680851 (-915 4160);
PAINT MONO (-915 4160);
FORCEPROP 0 LASTPIN (-925 2500) $PN 285
J 0
(-915 2510);
DISPLAY 0.680851 (-915 2510);
PAINT MONO (-915 2510);
FORCEPROP 0 LASTPIN (-925 4200) $PN 194
J 0
(-915 4210);
DISPLAY 0.680851 (-915 4210);
PAINT MONO (-915 4210);
FORCEPROP 0 LASTPIN (-925 2550) $PN 287
J 0
(-915 2560);
DISPLAY 0.680851 (-915 2560);
PAINT MONO (-915 2560);
FORCEPROP 0 LASTPIN (-2125 1700) $PN 148
J 2
(-2135 1710);
DISPLAY 0.680851 (-2135 1710);
PAINT MONO (-2135 1710);
FORCEPROP 0 LASTPIN (-2125 1600) $PN 4
J 2
(-2135 1610);
DISPLAY 0.680851 (-2135 1610);
PAINT MONO (-2135 1610);
FORCEPROP 0 LASTPIN (-2125 1650) $PN 5
J 2
(-2135 1660);
DISPLAY 0.680851 (-2135 1660);
PAINT MONO (-2135 1660);
FORCEPROP 0 LASTPIN (-2125 800) $PN 86
J 2
(-2135 810);
DISPLAY 0.680851 (-2135 810);
PAINT MONO (-2135 810);
FORCEPROP 0 LASTPIN (-2125 750) $PN 87
J 2
(-2135 760);
DISPLAY 0.680851 (-2135 760);
PAINT MONO (-2135 760);
FORCEPROP 0 LASTPIN (-2125 3400) $PN 74
J 2
(-2135 3410);
DISPLAY 0.680851 (-2135 3410);
PAINT MONO (-2135 3410);
FORCEPROP 0 LASTPIN (-2125 3350) $PN 227
J 2
(-2135 3360);
DISPLAY 0.680851 (-2135 3360);
PAINT MONO (-2135 3360);
FORCEPROP 0 LASTPIN (-2125 1350) $PN 147
J 2
(-2135 1360);
DISPLAY 0.680851 (-2135 1360);
PAINT MONO (-2135 1360);
FORCEPROP 0 LASTPIN (-2125 1900) $PN 207
J 2
(-2135 1910);
DISPLAY 0.680851 (-2135 1910);
PAINT MONO (-2135 1910);
FORCEPROP 0 LASTPIN (-2125 950) $PN 2
J 2
(-2135 960);
DISPLAY 0.680851 (-2135 960);
PAINT MONO (-2135 960);
FORCEPROP 0 LASTPIN (-2125 1000) $PN 144
J 2
(-2135 1010);
DISPLAY 0.680851 (-2135 1010);
PAINT MONO (-2135 1010);
FORCEPROP 0 LASTPIN (-2125 1050) $PN 149
J 2
(-2135 1060);
DISPLAY 0.680851 (-2135 1060);
PAINT MONO (-2135 1060);
FORCEPROP 0 LASTPIN (-2125 1100) $PN 150
J 2
(-2135 1110);
DISPLAY 0.680851 (-2135 1110);
PAINT MONO (-2135 1110);
FORCEPROP 0 LASTPIN (-2125 1150) $PN 220
J 2
(-2135 1160);
DISPLAY 0.680851 (-2135 1160);
PAINT MONO (-2135 1160);
FORCEPROP 0 LASTPIN (-2125 1200) $PN 231
J 2
(-2135 1210);
DISPLAY 0.680851 (-2135 1210);
PAINT MONO (-2135 1210);
FORCEPROP 0 LASTPIN (-2125 1250) $PN 232
J 2
(-2135 1260);
DISPLAY 0.680851 (-2135 1260);
PAINT MONO (-2135 1260);
FORCEPROP 0 LASTPIN (-2125 1750) $PN 3
J 2
(-2135 1760);
DISPLAY 0.680851 (-2135 1760);
PAINT MONO (-2135 1760);
FORCEPROP 1 LAST NEEDS_NO_SIZE TRUE
J 0
(-1525 2475);
DISPLAY 0.723404 (-1525 2475);
PAINT GREEN (-1525 2475);
DISPLAY INVISIBLE (-1525 2475);
FORCEPROP 1 LAST CDS_LMAN_SYM_OUTLINE -450,1875,450,-1875
J 0
(-1525 2475);
DISPLAY 0.468085 (-1525 2475);
PAINT GREEN (-1525 2475);
DISPLAY INVISIBLE (-1525 2475);
FORCEPROP 2 LAST CDS_LIB pure_quanta
J 0
(-1525 2475);
DISPLAY INVISIBLE (-1525 2475);
FORCEPROP 2 LAST CDS_LOCATION J8
J 0
(-1975 4700);
DISPLAY 1.021277 (-1975 4700);
DISPLAY INVISIBLE (-1975 4700);
FORCEPROP 0 LAST $SEC 1
J 0
(-1975 4700);
DISPLAY 0.680851 (-1975 4700);
PAINT MONO (-1975 4700);
DISPLAY INVISIBLE (-1975 4700);
FORCEPROP 2 LAST CDS_SEC 1
J 0
(-1975 4700);
DISPLAY 1.021277 (-1975 4700);
DISPLAY INVISIBLE (-1975 4700);
FORCEPROP 1 LAST PATH I50
J 0
(-1525 2475);
DISPLAY 0.723404 (-1525 2475);
PAINT GREEN (-1525 2475);
DISPLAY INVISIBLE (-1525 2475);
FORCEADD TAP..1
(-700 1000);
FORCEPROP 3 LASTPIN (-750 1000) SIG_NAME M_D_CPU0_SB_DQ<0>
J 0
(-740 1010);
DISPLAY 0.659574 (-740 1010);
PAINT MONO (-740 1010);
DISPLAY INVISIBLE (-740 1010);
FORCEPROP 1 LASTPIN (-750 1000) BN 0
J 0
(-762 1008);
DISPLAY 0.680851 (-762 1008);
PAINT GREEN (-762 1008);
FORCEPROP 2 LAST CDS_LIB standard
J 0
(-700 1000);
PAINT MONO (-700 1000);
DISPLAY INVISIBLE (-700 1000);
FORCEPROP 1 LAST BODY_TYPE PLUMBING
J 0
(-700 1050);
DISPLAY 0.872340 (-700 1050);
PAINT GREEN (-700 1050);
DISPLAY INVISIBLE (-700 1050);
FORCEPROP 1 LAST HDL_TAP TRUE
J 0
(-375 875);
DISPLAY 0.872340 (-375 875);
DISPLAY INVISIBLE (-375 875);
FORCEPROP 1 LAST PATH I51
J 0
(-702 1000);
DISPLAY 0.872340 (-702 1000);
PAINT GREEN (-702 1000);
DISPLAY INVISIBLE (-702 1000);
FORCEADD TAP..1
(-700 1050);
FORCEPROP 3 LASTPIN (-750 1050) SIG_NAME M_D_CPU0_SB_DQ<1>
J 0
(-740 1060);
DISPLAY 0.659574 (-740 1060);
PAINT MONO (-740 1060);
DISPLAY INVISIBLE (-740 1060);
FORCEPROP 1 LASTPIN (-750 1050) BN 1
J 0
(-762 1058);
DISPLAY 0.680851 (-762 1058);
PAINT GREEN (-762 1058);
FORCEPROP 2 LAST CDS_LIB standard
J 0
(-700 1050);
PAINT MONO (-700 1050);
DISPLAY INVISIBLE (-700 1050);
FORCEPROP 1 LAST BODY_TYPE PLUMBING
J 0
(-700 1100);
DISPLAY 0.872340 (-700 1100);
PAINT GREEN (-700 1100);
DISPLAY INVISIBLE (-700 1100);
FORCEPROP 1 LAST HDL_TAP TRUE
J 0
(-375 925);
DISPLAY 0.872340 (-375 925);
DISPLAY INVISIBLE (-375 925);
FORCEPROP 1 LAST PATH I52
J 0
(-702 1050);
DISPLAY 0.872340 (-702 1050);
PAINT GREEN (-702 1050);
DISPLAY INVISIBLE (-702 1050);
FORCEADD TAP..1
(-700 1150);
FORCEPROP 3 LASTPIN (-750 1150) SIG_NAME M_D_CPU0_SB_DQ<3>
J 0
(-740 1160);
DISPLAY 0.659574 (-740 1160);
PAINT MONO (-740 1160);
DISPLAY INVISIBLE (-740 1160);
FORCEPROP 1 LASTPIN (-750 1150) BN 3
J 0
(-762 1158);
DISPLAY 0.680851 (-762 1158);
PAINT GREEN (-762 1158);
FORCEPROP 2 LAST CDS_LIB standard
J 0
(-700 1150);
PAINT MONO (-700 1150);
DISPLAY INVISIBLE (-700 1150);
FORCEPROP 1 LAST BODY_TYPE PLUMBING
J 0
(-700 1200);
DISPLAY 0.872340 (-700 1200);
PAINT GREEN (-700 1200);
DISPLAY INVISIBLE (-700 1200);
FORCEPROP 1 LAST HDL_TAP TRUE
J 0
(-375 1025);
DISPLAY 0.872340 (-375 1025);
DISPLAY INVISIBLE (-375 1025);
FORCEPROP 1 LAST PATH I53
J 0
(-702 1150);
DISPLAY 0.872340 (-702 1150);
PAINT GREEN (-702 1150);
DISPLAY INVISIBLE (-702 1150);
FORCEADD TAP..1
(-700 1100);
FORCEPROP 3 LASTPIN (-750 1100) SIG_NAME M_D_CPU0_SB_DQ<2>
J 0
(-740 1110);
DISPLAY 0.659574 (-740 1110);
PAINT MONO (-740 1110);
DISPLAY INVISIBLE (-740 1110);
FORCEPROP 1 LASTPIN (-750 1100) BN 2
J 0
(-762 1108);
DISPLAY 0.680851 (-762 1108);
PAINT GREEN (-762 1108);
FORCEPROP 2 LAST CDS_LIB standard
J 0
(-700 1100);
PAINT MONO (-700 1100);
DISPLAY INVISIBLE (-700 1100);
FORCEPROP 1 LAST BODY_TYPE PLUMBING
J 0
(-700 1150);
DISPLAY 0.872340 (-700 1150);
PAINT GREEN (-700 1150);
DISPLAY INVISIBLE (-700 1150);
FORCEPROP 1 LAST HDL_TAP TRUE
J 0
(-375 975);
DISPLAY 0.872340 (-375 975);
DISPLAY INVISIBLE (-375 975);
FORCEPROP 1 LAST PATH I54
J 0
(-702 1100);
DISPLAY 0.872340 (-702 1100);
PAINT GREEN (-702 1100);
DISPLAY INVISIBLE (-702 1100);
FORCEADD TAP..1
(-700 1200);
FORCEPROP 3 LASTPIN (-750 1200) SIG_NAME M_D_CPU0_SB_DQ<4>
J 0
(-740 1210);
DISPLAY 0.659574 (-740 1210);
PAINT MONO (-740 1210);
DISPLAY INVISIBLE (-740 1210);
FORCEPROP 1 LASTPIN (-750 1200) BN 4
J 0
(-762 1208);
DISPLAY 0.680851 (-762 1208);
PAINT GREEN (-762 1208);
FORCEPROP 2 LAST CDS_LIB standard
J 0
(-700 1200);
PAINT MONO (-700 1200);
DISPLAY INVISIBLE (-700 1200);
FORCEPROP 1 LAST BODY_TYPE PLUMBING
J 0
(-700 1250);
DISPLAY 0.872340 (-700 1250);
PAINT GREEN (-700 1250);
DISPLAY INVISIBLE (-700 1250);
FORCEPROP 1 LAST HDL_TAP TRUE
J 0
(-375 1075);
DISPLAY 0.872340 (-375 1075);
DISPLAY INVISIBLE (-375 1075);
FORCEPROP 1 LAST PATH I55
J 0
(-702 1200);
DISPLAY 0.872340 (-702 1200);
PAINT GREEN (-702 1200);
DISPLAY INVISIBLE (-702 1200);
FORCEADD TAP..1
(-700 1250);
FORCEPROP 3 LASTPIN (-750 1250) SIG_NAME M_D_CPU0_SB_DQ<5>
J 0
(-740 1260);
DISPLAY 0.659574 (-740 1260);
PAINT MONO (-740 1260);
DISPLAY INVISIBLE (-740 1260);
FORCEPROP 1 LASTPIN (-750 1250) BN 5
J 0
(-762 1258);
DISPLAY 0.680851 (-762 1258);
PAINT GREEN (-762 1258);
FORCEPROP 2 LAST CDS_LIB standard
J 0
(-700 1250);
PAINT MONO (-700 1250);
DISPLAY INVISIBLE (-700 1250);
FORCEPROP 1 LAST BODY_TYPE PLUMBING
J 0
(-700 1300);
DISPLAY 0.872340 (-700 1300);
PAINT GREEN (-700 1300);
DISPLAY INVISIBLE (-700 1300);
FORCEPROP 1 LAST HDL_TAP TRUE
J 0
(-375 1125);
DISPLAY 0.872340 (-375 1125);
DISPLAY INVISIBLE (-375 1125);
FORCEPROP 1 LAST PATH I56
J 0
(-702 1250);
DISPLAY 0.872340 (-702 1250);
PAINT GREEN (-702 1250);
DISPLAY INVISIBLE (-702 1250);
FORCEADD TAP..1
(-700 1300);
FORCEPROP 3 LASTPIN (-750 1300) SIG_NAME M_D_CPU0_SB_DQ<6>
J 0
(-740 1310);
DISPLAY 0.659574 (-740 1310);
PAINT MONO (-740 1310);
DISPLAY INVISIBLE (-740 1310);
FORCEPROP 1 LASTPIN (-750 1300) BN 6
J 0
(-762 1308);
DISPLAY 0.680851 (-762 1308);
PAINT GREEN (-762 1308);
FORCEPROP 2 LAST CDS_LIB standard
J 0
(-700 1300);
PAINT MONO (-700 1300);
DISPLAY INVISIBLE (-700 1300);
FORCEPROP 1 LAST BODY_TYPE PLUMBING
J 0
(-700 1350);
DISPLAY 0.872340 (-700 1350);
PAINT GREEN (-700 1350);
DISPLAY INVISIBLE (-700 1350);
FORCEPROP 1 LAST HDL_TAP TRUE
J 0
(-375 1175);
DISPLAY 0.872340 (-375 1175);
DISPLAY INVISIBLE (-375 1175);
FORCEPROP 1 LAST PATH I57
J 0
(-702 1300);
DISPLAY 0.872340 (-702 1300);
PAINT GREEN (-702 1300);
DISPLAY INVISIBLE (-702 1300);
FORCEADD TAP..1
(-700 1400);
FORCEPROP 3 LASTPIN (-750 1400) SIG_NAME M_D_CPU0_SB_DQ<8>
J 0
(-740 1410);
DISPLAY 0.659574 (-740 1410);
PAINT MONO (-740 1410);
DISPLAY INVISIBLE (-740 1410);
FORCEPROP 1 LASTPIN (-750 1400) BN 8
J 0
(-762 1408);
DISPLAY 0.680851 (-762 1408);
PAINT GREEN (-762 1408);
FORCEPROP 2 LAST CDS_LIB standard
J 0
(-700 1400);
PAINT MONO (-700 1400);
DISPLAY INVISIBLE (-700 1400);
FORCEPROP 1 LAST BODY_TYPE PLUMBING
J 0
(-700 1450);
DISPLAY 0.872340 (-700 1450);
PAINT GREEN (-700 1450);
DISPLAY INVISIBLE (-700 1450);
FORCEPROP 1 LAST HDL_TAP TRUE
J 0
(-375 1275);
DISPLAY 0.872340 (-375 1275);
DISPLAY INVISIBLE (-375 1275);
FORCEPROP 1 LAST PATH I58
J 0
(-702 1400);
DISPLAY 0.872340 (-702 1400);
PAINT GREEN (-702 1400);
DISPLAY INVISIBLE (-702 1400);
FORCEADD TAP..1
(-700 1350);
FORCEPROP 3 LASTPIN (-750 1350) SIG_NAME M_D_CPU0_SB_DQ<7>
J 0
(-740 1360);
DISPLAY 0.659574 (-740 1360);
PAINT MONO (-740 1360);
DISPLAY INVISIBLE (-740 1360);
FORCEPROP 1 LASTPIN (-750 1350) BN 7
J 0
(-762 1358);
DISPLAY 0.680851 (-762 1358);
PAINT GREEN (-762 1358);
FORCEPROP 2 LAST CDS_LIB standard
J 0
(-700 1350);
PAINT MONO (-700 1350);
DISPLAY INVISIBLE (-700 1350);
FORCEPROP 1 LAST BODY_TYPE PLUMBING
J 0
(-700 1400);
DISPLAY 0.872340 (-700 1400);
PAINT GREEN (-700 1400);
DISPLAY INVISIBLE (-700 1400);
FORCEPROP 1 LAST HDL_TAP TRUE
J 0
(-375 1225);
DISPLAY 0.872340 (-375 1225);
DISPLAY INVISIBLE (-375 1225);
FORCEPROP 1 LAST PATH I59
J 0
(-702 1350);
DISPLAY 0.872340 (-702 1350);
PAINT GREEN (-702 1350);
DISPLAY INVISIBLE (-702 1350);
FORCEADD TAP..1
(-700 1450);
FORCEPROP 3 LASTPIN (-750 1450) SIG_NAME M_D_CPU0_SB_DQ<9>
J 0
(-740 1460);
DISPLAY 0.659574 (-740 1460);
PAINT MONO (-740 1460);
DISPLAY INVISIBLE (-740 1460);
FORCEPROP 1 LASTPIN (-750 1450) BN 9
J 0
(-762 1458);
DISPLAY 0.680851 (-762 1458);
PAINT GREEN (-762 1458);
FORCEPROP 2 LAST CDS_LIB standard
J 0
(-700 1450);
PAINT MONO (-700 1450);
DISPLAY INVISIBLE (-700 1450);
FORCEPROP 1 LAST BODY_TYPE PLUMBING
J 0
(-700 1500);
DISPLAY 0.872340 (-700 1500);
PAINT GREEN (-700 1500);
DISPLAY INVISIBLE (-700 1500);
FORCEPROP 1 LAST HDL_TAP TRUE
J 0
(-375 1325);
DISPLAY 0.872340 (-375 1325);
DISPLAY INVISIBLE (-375 1325);
FORCEPROP 1 LAST PATH I60
J 0
(-702 1450);
DISPLAY 0.872340 (-702 1450);
PAINT GREEN (-702 1450);
DISPLAY INVISIBLE (-702 1450);
FORCEADD TAP..1
(-700 1500);
FORCEPROP 3 LASTPIN (-750 1500) SIG_NAME M_D_CPU0_SB_DQ<10>
J 0
(-740 1510);
DISPLAY 0.659574 (-740 1510);
PAINT MONO (-740 1510);
DISPLAY INVISIBLE (-740 1510);
FORCEPROP 1 LASTPIN (-750 1500) BN 10
J 0
(-762 1508);
DISPLAY 0.680851 (-762 1508);
PAINT GREEN (-762 1508);
FORCEPROP 2 LAST CDS_LIB standard
J 0
(-700 1500);
PAINT MONO (-700 1500);
DISPLAY INVISIBLE (-700 1500);
FORCEPROP 1 LAST BODY_TYPE PLUMBING
J 0
(-700 1550);
DISPLAY 0.872340 (-700 1550);
PAINT GREEN (-700 1550);
DISPLAY INVISIBLE (-700 1550);
FORCEPROP 1 LAST HDL_TAP TRUE
J 0
(-375 1375);
DISPLAY 0.872340 (-375 1375);
DISPLAY INVISIBLE (-375 1375);
FORCEPROP 1 LAST PATH I61
J 0
(-702 1500);
DISPLAY 0.872340 (-702 1500);
PAINT GREEN (-702 1500);
DISPLAY INVISIBLE (-702 1500);
FORCEADD TAP..1
(-700 1550);
FORCEPROP 3 LASTPIN (-750 1550) SIG_NAME M_D_CPU0_SB_DQ<11>
J 0
(-740 1560);
DISPLAY 0.659574 (-740 1560);
PAINT MONO (-740 1560);
DISPLAY INVISIBLE (-740 1560);
FORCEPROP 1 LASTPIN (-750 1550) BN 11
J 0
(-762 1558);
DISPLAY 0.680851 (-762 1558);
PAINT GREEN (-762 1558);
FORCEPROP 2 LAST CDS_LIB standard
J 0
(-700 1550);
PAINT MONO (-700 1550);
DISPLAY INVISIBLE (-700 1550);
FORCEPROP 1 LAST BODY_TYPE PLUMBING
J 0
(-700 1600);
DISPLAY 0.872340 (-700 1600);
PAINT GREEN (-700 1600);
DISPLAY INVISIBLE (-700 1600);
FORCEPROP 1 LAST HDL_TAP TRUE
J 0
(-375 1425);
DISPLAY 0.872340 (-375 1425);
DISPLAY INVISIBLE (-375 1425);
FORCEPROP 1 LAST PATH I62
J 0
(-702 1550);
DISPLAY 0.872340 (-702 1550);
PAINT GREEN (-702 1550);
DISPLAY INVISIBLE (-702 1550);
FORCEADD TAP..1
(-700 1600);
FORCEPROP 3 LASTPIN (-750 1600) SIG_NAME M_D_CPU0_SB_DQ<12>
J 0
(-740 1610);
DISPLAY 0.659574 (-740 1610);
PAINT MONO (-740 1610);
DISPLAY INVISIBLE (-740 1610);
FORCEPROP 1 LASTPIN (-750 1600) BN 12
J 0
(-762 1608);
DISPLAY 0.680851 (-762 1608);
PAINT GREEN (-762 1608);
FORCEPROP 2 LAST CDS_LIB standard
J 0
(-700 1600);
PAINT MONO (-700 1600);
DISPLAY INVISIBLE (-700 1600);
FORCEPROP 1 LAST BODY_TYPE PLUMBING
J 0
(-700 1650);
DISPLAY 0.872340 (-700 1650);
PAINT GREEN (-700 1650);
DISPLAY INVISIBLE (-700 1650);
FORCEPROP 1 LAST HDL_TAP TRUE
J 0
(-375 1475);
DISPLAY 0.872340 (-375 1475);
DISPLAY INVISIBLE (-375 1475);
FORCEPROP 1 LAST PATH I63
J 0
(-702 1600);
DISPLAY 0.872340 (-702 1600);
PAINT GREEN (-702 1600);
DISPLAY INVISIBLE (-702 1600);
FORCEADD TAP..1
(-700 1650);
FORCEPROP 3 LASTPIN (-750 1650) SIG_NAME M_D_CPU0_SB_DQ<13>
J 0
(-740 1660);
DISPLAY 0.659574 (-740 1660);
PAINT MONO (-740 1660);
DISPLAY INVISIBLE (-740 1660);
FORCEPROP 1 LASTPIN (-750 1650) BN 13
J 0
(-762 1658);
DISPLAY 0.680851 (-762 1658);
PAINT GREEN (-762 1658);
FORCEPROP 2 LAST CDS_LIB standard
J 0
(-700 1650);
PAINT MONO (-700 1650);
DISPLAY INVISIBLE (-700 1650);
FORCEPROP 1 LAST BODY_TYPE PLUMBING
J 0
(-700 1700);
DISPLAY 0.872340 (-700 1700);
PAINT GREEN (-700 1700);
DISPLAY INVISIBLE (-700 1700);
FORCEPROP 1 LAST HDL_TAP TRUE
J 0
(-375 1525);
DISPLAY 0.872340 (-375 1525);
DISPLAY INVISIBLE (-375 1525);
FORCEPROP 1 LAST PATH I64
J 0
(-702 1650);
DISPLAY 0.872340 (-702 1650);
PAINT GREEN (-702 1650);
DISPLAY INVISIBLE (-702 1650);
FORCEADD TAP..1
(-700 1700);
FORCEPROP 3 LASTPIN (-750 1700) SIG_NAME M_D_CPU0_SB_DQ<14>
J 0
(-740 1710);
DISPLAY 0.659574 (-740 1710);
PAINT MONO (-740 1710);
DISPLAY INVISIBLE (-740 1710);
FORCEPROP 1 LASTPIN (-750 1700) BN 14
J 0
(-762 1708);
DISPLAY 0.680851 (-762 1708);
PAINT GREEN (-762 1708);
FORCEPROP 2 LAST CDS_LIB standard
J 0
(-700 1700);
PAINT MONO (-700 1700);
DISPLAY INVISIBLE (-700 1700);
FORCEPROP 1 LAST BODY_TYPE PLUMBING
J 0
(-700 1750);
DISPLAY 0.872340 (-700 1750);
PAINT GREEN (-700 1750);
DISPLAY INVISIBLE (-700 1750);
FORCEPROP 1 LAST HDL_TAP TRUE
J 0
(-375 1575);
DISPLAY 0.872340 (-375 1575);
DISPLAY INVISIBLE (-375 1575);
FORCEPROP 1 LAST PATH I65
J 0
(-702 1700);
DISPLAY 0.872340 (-702 1700);
PAINT GREEN (-702 1700);
DISPLAY INVISIBLE (-702 1700);
FORCEADD TAP..1
(-700 1750);
FORCEPROP 3 LASTPIN (-750 1750) SIG_NAME M_D_CPU0_SB_DQ<15>
J 0
(-740 1760);
DISPLAY 0.659574 (-740 1760);
PAINT MONO (-740 1760);
DISPLAY INVISIBLE (-740 1760);
FORCEPROP 1 LASTPIN (-750 1750) BN 15
J 0
(-762 1758);
DISPLAY 0.680851 (-762 1758);
PAINT GREEN (-762 1758);
FORCEPROP 2 LAST CDS_LIB standard
J 0
(-700 1750);
PAINT MONO (-700 1750);
DISPLAY INVISIBLE (-700 1750);
FORCEPROP 1 LAST BODY_TYPE PLUMBING
J 0
(-700 1800);
DISPLAY 0.872340 (-700 1800);
PAINT GREEN (-700 1800);
DISPLAY INVISIBLE (-700 1800);
FORCEPROP 1 LAST HDL_TAP TRUE
J 0
(-375 1625);
DISPLAY 0.872340 (-375 1625);
DISPLAY INVISIBLE (-375 1625);
FORCEPROP 1 LAST PATH I66
J 0
(-702 1750);
DISPLAY 0.872340 (-702 1750);
PAINT GREEN (-702 1750);
DISPLAY INVISIBLE (-702 1750);
FORCEADD TAP..1
(-700 1850);
FORCEPROP 3 LASTPIN (-750 1850) SIG_NAME M_D_CPU0_SB_DQ<17>
J 0
(-740 1860);
DISPLAY 0.659574 (-740 1860);
PAINT MONO (-740 1860);
DISPLAY INVISIBLE (-740 1860);
FORCEPROP 1 LASTPIN (-750 1850) BN 17
J 0
(-762 1858);
DISPLAY 0.680851 (-762 1858);
PAINT GREEN (-762 1858);
FORCEPROP 2 LAST CDS_LIB standard
J 0
(-700 1850);
PAINT MONO (-700 1850);
DISPLAY INVISIBLE (-700 1850);
FORCEPROP 1 LAST BODY_TYPE PLUMBING
J 0
(-700 1900);
DISPLAY 0.872340 (-700 1900);
PAINT GREEN (-700 1900);
DISPLAY INVISIBLE (-700 1900);
FORCEPROP 1 LAST HDL_TAP TRUE
J 0
(-375 1725);
DISPLAY 0.872340 (-375 1725);
DISPLAY INVISIBLE (-375 1725);
FORCEPROP 1 LAST PATH I67
J 0
(-702 1850);
DISPLAY 0.872340 (-702 1850);
PAINT GREEN (-702 1850);
DISPLAY INVISIBLE (-702 1850);
FORCEADD TAP..1
(-700 1800);
FORCEPROP 3 LASTPIN (-750 1800) SIG_NAME M_D_CPU0_SB_DQ<16>
J 0
(-740 1810);
DISPLAY 0.659574 (-740 1810);
PAINT MONO (-740 1810);
DISPLAY INVISIBLE (-740 1810);
FORCEPROP 1 LASTPIN (-750 1800) BN 16
J 0
(-762 1808);
DISPLAY 0.680851 (-762 1808);
PAINT GREEN (-762 1808);
FORCEPROP 2 LAST CDS_LIB standard
J 0
(-700 1800);
PAINT MONO (-700 1800);
DISPLAY INVISIBLE (-700 1800);
FORCEPROP 1 LAST BODY_TYPE PLUMBING
J 0
(-700 1850);
DISPLAY 0.872340 (-700 1850);
PAINT GREEN (-700 1850);
DISPLAY INVISIBLE (-700 1850);
FORCEPROP 1 LAST HDL_TAP TRUE
J 0
(-375 1675);
DISPLAY 0.872340 (-375 1675);
DISPLAY INVISIBLE (-375 1675);
FORCEPROP 1 LAST PATH I68
J 0
(-702 1800);
DISPLAY 0.872340 (-702 1800);
PAINT GREEN (-702 1800);
DISPLAY INVISIBLE (-702 1800);
FORCEADD TAP..1
(-700 1900);
FORCEPROP 3 LASTPIN (-750 1900) SIG_NAME M_D_CPU0_SB_DQ<18>
J 0
(-740 1910);
DISPLAY 0.659574 (-740 1910);
PAINT MONO (-740 1910);
DISPLAY INVISIBLE (-740 1910);
FORCEPROP 1 LASTPIN (-750 1900) BN 18
J 0
(-762 1908);
DISPLAY 0.680851 (-762 1908);
PAINT GREEN (-762 1908);
FORCEPROP 2 LAST CDS_LIB standard
J 0
(-700 1900);
PAINT MONO (-700 1900);
DISPLAY INVISIBLE (-700 1900);
FORCEPROP 1 LAST BODY_TYPE PLUMBING
J 0
(-700 1950);
DISPLAY 0.872340 (-700 1950);
PAINT GREEN (-700 1950);
DISPLAY INVISIBLE (-700 1950);
FORCEPROP 1 LAST HDL_TAP TRUE
J 0
(-375 1775);
DISPLAY 0.872340 (-375 1775);
DISPLAY INVISIBLE (-375 1775);
FORCEPROP 1 LAST PATH I69
J 0
(-702 1900);
DISPLAY 0.872340 (-702 1900);
PAINT GREEN (-702 1900);
DISPLAY INVISIBLE (-702 1900);
FORCEADD OFFPAGE..1
(-3200 1650);
FORCEPROP 2 LAST $XR7 88 
J 0
(-3662 1686);
DISPLAY 0.638298 (-3662 1686);
PAINT MONO (-3662 1686);
FORCEPROP 2 LAST $XR6 87 
J 0
(-3572 1686);
DISPLAY 0.638298 (-3572 1686);
PAINT MONO (-3572 1686);
FORCEPROP 2 LAST $XR5 86 
J 0
(-3662 1614);
DISPLAY 0.638298 (-3662 1614);
PAINT MONO (-3662 1614);
FORCEPROP 2 LAST $XR4 85 
J 0
(-3572 1614);
DISPLAY 0.638298 (-3572 1614);
PAINT MONO (-3572 1614);
FORCEPROP 2 LAST $XR3 84 
J 0
(-3482 1614);
DISPLAY 0.638298 (-3482 1614);
PAINT MONO (-3482 1614);
FORCEPROP 2 LAST $XR2 83 
J 0
(-3662 1650);
DISPLAY 0.638298 (-3662 1650);
PAINT MONO (-3662 1650);
FORCEPROP 2 LAST $XR1 82 
J 0
(-3572 1650);
DISPLAY 0.638298 (-3572 1650);
PAINT MONO (-3572 1650);
FORCEPROP 2 LAST $XR0 229 
J 0
(-3482 1650);
DISPLAY 0.638298 (-3482 1650);
PAINT MONO (-3482 1650);
FORCEPROP 2 LAST CDS_LIB standard
J 0
(-3200 1650);
PAINT MONO (-3200 1650);
DISPLAY INVISIBLE (-3200 1650);
FORCEPROP 1 LAST OFFPAGE TRUE
J 0
(-2875 1525);
DISPLAY 0.872340 (-2875 1525);
DISPLAY INVISIBLE (-2875 1525);
FORCEPROP 1 LAST COMMENT_BODY TRUE
J 0
(-3075 1550);
DISPLAY 0.872340 (-3075 1550);
PAINT GREEN (-3075 1550);
DISPLAY INVISIBLE (-3075 1550);
FORCEPROP 2 LAST PATH I7
J 0
(-3150 1725);
DISPLAY 1.021277 (-3150 1725);
DISPLAY INVISIBLE (-3150 1725);
FORCEADD TAP..1
(-700 1950);
FORCEPROP 3 LASTPIN (-750 1950) SIG_NAME M_D_CPU0_SB_DQ<19>
J 0
(-740 1960);
DISPLAY 0.659574 (-740 1960);
PAINT MONO (-740 1960);
DISPLAY INVISIBLE (-740 1960);
FORCEPROP 1 LASTPIN (-750 1950) BN 19
J 0
(-762 1958);
DISPLAY 0.680851 (-762 1958);
PAINT GREEN (-762 1958);
FORCEPROP 2 LAST CDS_LIB standard
J 0
(-700 1950);
PAINT MONO (-700 1950);
DISPLAY INVISIBLE (-700 1950);
FORCEPROP 1 LAST BODY_TYPE PLUMBING
J 0
(-700 2000);
DISPLAY 0.872340 (-700 2000);
PAINT GREEN (-700 2000);
DISPLAY INVISIBLE (-700 2000);
FORCEPROP 1 LAST HDL_TAP TRUE
J 0
(-375 1825);
DISPLAY 0.872340 (-375 1825);
DISPLAY INVISIBLE (-375 1825);
FORCEPROP 1 LAST PATH I70
J 0
(-702 1950);
DISPLAY 0.872340 (-702 1950);
PAINT GREEN (-702 1950);
DISPLAY INVISIBLE (-702 1950);
FORCEADD TAP..1
(-700 2000);
FORCEPROP 3 LASTPIN (-750 2000) SIG_NAME M_D_CPU0_SB_DQ<20>
J 0
(-740 2010);
DISPLAY 0.659574 (-740 2010);
PAINT MONO (-740 2010);
DISPLAY INVISIBLE (-740 2010);
FORCEPROP 1 LASTPIN (-750 2000) BN 20
J 0
(-762 2008);
DISPLAY 0.680851 (-762 2008);
PAINT GREEN (-762 2008);
FORCEPROP 2 LAST CDS_LIB standard
J 0
(-700 2000);
PAINT MONO (-700 2000);
DISPLAY INVISIBLE (-700 2000);
FORCEPROP 1 LAST BODY_TYPE PLUMBING
J 0
(-700 2050);
DISPLAY 0.872340 (-700 2050);
PAINT GREEN (-700 2050);
DISPLAY INVISIBLE (-700 2050);
FORCEPROP 1 LAST HDL_TAP TRUE
J 0
(-375 1875);
DISPLAY 0.872340 (-375 1875);
DISPLAY INVISIBLE (-375 1875);
FORCEPROP 1 LAST PATH I71
J 0
(-702 2000);
DISPLAY 0.872340 (-702 2000);
PAINT GREEN (-702 2000);
DISPLAY INVISIBLE (-702 2000);
FORCEADD TAP..1
(-700 2050);
FORCEPROP 3 LASTPIN (-750 2050) SIG_NAME M_D_CPU0_SB_DQ<21>
J 0
(-740 2060);
DISPLAY 0.659574 (-740 2060);
PAINT MONO (-740 2060);
DISPLAY INVISIBLE (-740 2060);
FORCEPROP 1 LASTPIN (-750 2050) BN 21
J 0
(-762 2058);
DISPLAY 0.680851 (-762 2058);
PAINT GREEN (-762 2058);
FORCEPROP 2 LAST CDS_LIB standard
J 0
(-700 2050);
PAINT MONO (-700 2050);
DISPLAY INVISIBLE (-700 2050);
FORCEPROP 1 LAST BODY_TYPE PLUMBING
J 0
(-700 2100);
DISPLAY 0.872340 (-700 2100);
PAINT GREEN (-700 2100);
DISPLAY INVISIBLE (-700 2100);
FORCEPROP 1 LAST HDL_TAP TRUE
J 0
(-375 1925);
DISPLAY 0.872340 (-375 1925);
DISPLAY INVISIBLE (-375 1925);
FORCEPROP 1 LAST PATH I72
J 0
(-702 2050);
DISPLAY 0.872340 (-702 2050);
PAINT GREEN (-702 2050);
DISPLAY INVISIBLE (-702 2050);
FORCEADD TAP..1
(-700 2100);
FORCEPROP 3 LASTPIN (-750 2100) SIG_NAME M_D_CPU0_SB_DQ<22>
J 0
(-740 2110);
DISPLAY 0.659574 (-740 2110);
PAINT MONO (-740 2110);
DISPLAY INVISIBLE (-740 2110);
FORCEPROP 1 LASTPIN (-750 2100) BN 22
J 0
(-762 2108);
DISPLAY 0.680851 (-762 2108);
PAINT GREEN (-762 2108);
FORCEPROP 2 LAST CDS_LIB standard
J 0
(-700 2100);
DISPLAY INVISIBLE (-700 2100);
FORCEPROP 1 LAST BODY_TYPE PLUMBING
J 0
(-700 2150);
DISPLAY 0.872340 (-700 2150);
PAINT GREEN (-700 2150);
DISPLAY INVISIBLE (-700 2150);
FORCEPROP 1 LAST HDL_TAP TRUE
J 0
(-375 1975);
DISPLAY 0.872340 (-375 1975);
DISPLAY INVISIBLE (-375 1975);
FORCEPROP 1 LAST PATH I73
J 0
(-702 2100);
DISPLAY 0.872340 (-702 2100);
PAINT GREEN (-702 2100);
DISPLAY INVISIBLE (-702 2100);
FORCEADD TAP..1
(-700 2150);
FORCEPROP 3 LASTPIN (-750 2150) SIG_NAME M_D_CPU0_SB_DQ<23>
J 0
(-740 2160);
DISPLAY 0.659574 (-740 2160);
PAINT MONO (-740 2160);
DISPLAY INVISIBLE (-740 2160);
FORCEPROP 1 LASTPIN (-750 2150) BN 23
J 0
(-762 2158);
DISPLAY 0.680851 (-762 2158);
PAINT GREEN (-762 2158);
FORCEPROP 2 LAST CDS_LIB standard
J 0
(-700 2150);
DISPLAY INVISIBLE (-700 2150);
FORCEPROP 1 LAST BODY_TYPE PLUMBING
J 0
(-700 2200);
DISPLAY 0.872340 (-700 2200);
PAINT GREEN (-700 2200);
DISPLAY INVISIBLE (-700 2200);
FORCEPROP 1 LAST HDL_TAP TRUE
J 0
(-375 2025);
DISPLAY 0.872340 (-375 2025);
DISPLAY INVISIBLE (-375 2025);
FORCEPROP 1 LAST PATH I74
J 0
(-702 2150);
DISPLAY 0.872340 (-702 2150);
PAINT GREEN (-702 2150);
DISPLAY INVISIBLE (-702 2150);
FORCEADD TAP..1
(-700 2200);
FORCEPROP 3 LASTPIN (-750 2200) SIG_NAME M_D_CPU0_SB_DQ<24>
J 0
(-740 2210);
DISPLAY 0.659574 (-740 2210);
PAINT MONO (-740 2210);
DISPLAY INVISIBLE (-740 2210);
FORCEPROP 1 LASTPIN (-750 2200) BN 24
J 0
(-762 2208);
DISPLAY 0.680851 (-762 2208);
PAINT GREEN (-762 2208);
FORCEPROP 2 LAST CDS_LIB standard
J 0
(-700 2200);
DISPLAY INVISIBLE (-700 2200);
FORCEPROP 1 LAST BODY_TYPE PLUMBING
J 0
(-700 2250);
DISPLAY 0.872340 (-700 2250);
PAINT GREEN (-700 2250);
DISPLAY INVISIBLE (-700 2250);
FORCEPROP 1 LAST HDL_TAP TRUE
J 0
(-375 2075);
DISPLAY 0.872340 (-375 2075);
DISPLAY INVISIBLE (-375 2075);
FORCEPROP 1 LAST PATH I75
J 0
(-702 2200);
DISPLAY 0.872340 (-702 2200);
PAINT GREEN (-702 2200);
DISPLAY INVISIBLE (-702 2200);
FORCEADD TAP..1
(-700 2300);
FORCEPROP 3 LASTPIN (-750 2300) SIG_NAME M_D_CPU0_SB_DQ<26>
J 0
(-740 2310);
DISPLAY 0.659574 (-740 2310);
PAINT MONO (-740 2310);
DISPLAY INVISIBLE (-740 2310);
FORCEPROP 1 LASTPIN (-750 2300) BN 26
J 0
(-762 2308);
DISPLAY 0.680851 (-762 2308);
PAINT GREEN (-762 2308);
FORCEPROP 2 LAST CDS_LIB standard
J 0
(-700 2300);
DISPLAY INVISIBLE (-700 2300);
FORCEPROP 1 LAST BODY_TYPE PLUMBING
J 0
(-700 2350);
DISPLAY 0.872340 (-700 2350);
PAINT GREEN (-700 2350);
DISPLAY INVISIBLE (-700 2350);
FORCEPROP 1 LAST HDL_TAP TRUE
J 0
(-375 2175);
DISPLAY 0.872340 (-375 2175);
DISPLAY INVISIBLE (-375 2175);
FORCEPROP 1 LAST PATH I76
J 0
(-702 2300);
DISPLAY 0.872340 (-702 2300);
PAINT GREEN (-702 2300);
DISPLAY INVISIBLE (-702 2300);
FORCEADD TAP..1
(-700 2250);
FORCEPROP 3 LASTPIN (-750 2250) SIG_NAME M_D_CPU0_SB_DQ<25>
J 0
(-740 2260);
DISPLAY 0.659574 (-740 2260);
PAINT MONO (-740 2260);
DISPLAY INVISIBLE (-740 2260);
FORCEPROP 1 LASTPIN (-750 2250) BN 25
J 0
(-762 2258);
DISPLAY 0.680851 (-762 2258);
PAINT GREEN (-762 2258);
FORCEPROP 2 LAST CDS_LIB standard
J 0
(-700 2250);
DISPLAY INVISIBLE (-700 2250);
FORCEPROP 1 LAST BODY_TYPE PLUMBING
J 0
(-700 2300);
DISPLAY 0.872340 (-700 2300);
PAINT GREEN (-700 2300);
DISPLAY INVISIBLE (-700 2300);
FORCEPROP 1 LAST HDL_TAP TRUE
J 0
(-375 2125);
DISPLAY 0.872340 (-375 2125);
DISPLAY INVISIBLE (-375 2125);
FORCEPROP 1 LAST PATH I77
J 0
(-702 2250);
DISPLAY 0.872340 (-702 2250);
PAINT GREEN (-702 2250);
DISPLAY INVISIBLE (-702 2250);
FORCEADD TAP..1
(-700 2350);
FORCEPROP 3 LASTPIN (-750 2350) SIG_NAME M_D_CPU0_SB_DQ<27>
J 0
(-740 2360);
DISPLAY 0.659574 (-740 2360);
PAINT MONO (-740 2360);
DISPLAY INVISIBLE (-740 2360);
FORCEPROP 1 LASTPIN (-750 2350) BN 27
J 0
(-762 2358);
DISPLAY 0.680851 (-762 2358);
PAINT GREEN (-762 2358);
FORCEPROP 2 LAST CDS_LIB standard
J 0
(-700 2350);
DISPLAY INVISIBLE (-700 2350);
FORCEPROP 1 LAST BODY_TYPE PLUMBING
J 0
(-700 2400);
DISPLAY 0.872340 (-700 2400);
PAINT GREEN (-700 2400);
DISPLAY INVISIBLE (-700 2400);
FORCEPROP 1 LAST HDL_TAP TRUE
J 0
(-375 2225);
DISPLAY 0.872340 (-375 2225);
DISPLAY INVISIBLE (-375 2225);
FORCEPROP 1 LAST PATH I78
J 0
(-702 2350);
DISPLAY 0.872340 (-702 2350);
PAINT GREEN (-702 2350);
DISPLAY INVISIBLE (-702 2350);
FORCEADD TAP..1
(-700 2400);
FORCEPROP 3 LASTPIN (-750 2400) SIG_NAME M_D_CPU0_SB_DQ<28>
J 0
(-740 2410);
DISPLAY 0.659574 (-740 2410);
PAINT MONO (-740 2410);
DISPLAY INVISIBLE (-740 2410);
FORCEPROP 1 LASTPIN (-750 2400) BN 28
J 0
(-762 2408);
DISPLAY 0.680851 (-762 2408);
PAINT GREEN (-762 2408);
FORCEPROP 2 LAST CDS_LIB standard
J 0
(-700 2400);
DISPLAY INVISIBLE (-700 2400);
FORCEPROP 1 LAST BODY_TYPE PLUMBING
J 0
(-700 2450);
DISPLAY 0.872340 (-700 2450);
PAINT GREEN (-700 2450);
DISPLAY INVISIBLE (-700 2450);
FORCEPROP 1 LAST HDL_TAP TRUE
J 0
(-375 2275);
DISPLAY 0.872340 (-375 2275);
DISPLAY INVISIBLE (-375 2275);
FORCEPROP 1 LAST PATH I79
J 0
(-702 2400);
DISPLAY 0.872340 (-702 2400);
PAINT GREEN (-702 2400);
DISPLAY INVISIBLE (-702 2400);
FORCEADD OFFPAGE..1
(-3200 1700);
FORCEPROP 2 LAST $XR0 89 
J 0
(-3451 1700);
DISPLAY 0.638298 (-3451 1700);
PAINT MONO (-3451 1700);
FORCEPROP 2 LAST CDS_LIB standard
J 0
(-3200 1700);
PAINT MONO (-3200 1700);
DISPLAY INVISIBLE (-3200 1700);
FORCEPROP 1 LAST OFFPAGE TRUE
J 0
(-2875 1575);
DISPLAY 0.872340 (-2875 1575);
DISPLAY INVISIBLE (-2875 1575);
FORCEPROP 1 LAST COMMENT_BODY TRUE
J 0
(-3075 1600);
DISPLAY 0.872340 (-3075 1600);
PAINT GREEN (-3075 1600);
DISPLAY INVISIBLE (-3075 1600);
FORCEPROP 2 LAST PATH I8
J 0
(-3150 1775);
DISPLAY 1.021277 (-3150 1775);
DISPLAY INVISIBLE (-3150 1775);
FORCEADD TAP..1
(-700 2450);
FORCEPROP 3 LASTPIN (-750 2450) SIG_NAME M_D_CPU0_SB_DQ<29>
J 0
(-740 2460);
DISPLAY 0.659574 (-740 2460);
PAINT MONO (-740 2460);
DISPLAY INVISIBLE (-740 2460);
FORCEPROP 1 LASTPIN (-750 2450) BN 29
J 0
(-762 2458);
DISPLAY 0.680851 (-762 2458);
PAINT GREEN (-762 2458);
FORCEPROP 2 LAST CDS_LIB standard
J 0
(-700 2450);
DISPLAY INVISIBLE (-700 2450);
FORCEPROP 1 LAST BODY_TYPE PLUMBING
J 0
(-700 2500);
DISPLAY 0.872340 (-700 2500);
PAINT GREEN (-700 2500);
DISPLAY INVISIBLE (-700 2500);
FORCEPROP 1 LAST HDL_TAP TRUE
J 0
(-375 2325);
DISPLAY 0.872340 (-375 2325);
DISPLAY INVISIBLE (-375 2325);
FORCEPROP 1 LAST PATH I80
J 0
(-702 2450);
DISPLAY 0.872340 (-702 2450);
PAINT GREEN (-702 2450);
DISPLAY INVISIBLE (-702 2450);
FORCEADD TAP..1
(-700 2550);
FORCEPROP 3 LASTPIN (-750 2550) SIG_NAME M_D_CPU0_SB_DQ<31>
J 0
(-740 2560);
DISPLAY 0.659574 (-740 2560);
PAINT MONO (-740 2560);
DISPLAY INVISIBLE (-740 2560);
FORCEPROP 1 LASTPIN (-750 2550) BN 31
J 0
(-762 2558);
DISPLAY 0.680851 (-762 2558);
PAINT GREEN (-762 2558);
FORCEPROP 2 LAST CDS_LIB standard
J 0
(-700 2550);
DISPLAY INVISIBLE (-700 2550);
FORCEPROP 1 LAST BODY_TYPE PLUMBING
J 0
(-700 2600);
DISPLAY 0.872340 (-700 2600);
PAINT GREEN (-700 2600);
DISPLAY INVISIBLE (-700 2600);
FORCEPROP 1 LAST HDL_TAP TRUE
J 0
(-375 2425);
DISPLAY 0.872340 (-375 2425);
DISPLAY INVISIBLE (-375 2425);
FORCEPROP 1 LAST PATH I81
J 0
(-702 2550);
DISPLAY 0.872340 (-702 2550);
PAINT GREEN (-702 2550);
DISPLAY INVISIBLE (-702 2550);
FORCEADD TAP..1
(-700 2500);
FORCEPROP 3 LASTPIN (-750 2500) SIG_NAME M_D_CPU0_SB_DQ<30>
J 0
(-740 2510);
DISPLAY 0.659574 (-740 2510);
PAINT MONO (-740 2510);
DISPLAY INVISIBLE (-740 2510);
FORCEPROP 1 LASTPIN (-750 2500) BN 30
J 0
(-762 2508);
DISPLAY 0.680851 (-762 2508);
PAINT GREEN (-762 2508);
FORCEPROP 2 LAST CDS_LIB standard
J 0
(-700 2500);
DISPLAY INVISIBLE (-700 2500);
FORCEPROP 1 LAST BODY_TYPE PLUMBING
J 0
(-700 2550);
DISPLAY 0.872340 (-700 2550);
PAINT GREEN (-700 2550);
DISPLAY INVISIBLE (-700 2550);
FORCEPROP 1 LAST HDL_TAP TRUE
J 0
(-375 2375);
DISPLAY 0.872340 (-375 2375);
DISPLAY INVISIBLE (-375 2375);
FORCEPROP 1 LAST PATH I82
J 0
(-702 2500);
DISPLAY 0.872340 (-702 2500);
PAINT GREEN (-702 2500);
DISPLAY INVISIBLE (-702 2500);
FORCEADD TAP..1
(-700 2650);
FORCEPROP 3 LASTPIN (-750 2650) SIG_NAME M_D_CPU0_SA_DQ<0>
J 0
(-740 2660);
DISPLAY 0.659574 (-740 2660);
PAINT MONO (-740 2660);
DISPLAY INVISIBLE (-740 2660);
FORCEPROP 1 LASTPIN (-750 2650) BN 0
J 0
(-762 2658);
DISPLAY 0.680851 (-762 2658);
PAINT GREEN (-762 2658);
FORCEPROP 2 LAST CDS_LIB standard
J 0
(-700 2650);
PAINT MONO (-700 2650);
DISPLAY INVISIBLE (-700 2650);
FORCEPROP 1 LAST BODY_TYPE PLUMBING
J 0
(-700 2700);
DISPLAY 0.872340 (-700 2700);
PAINT GREEN (-700 2700);
DISPLAY INVISIBLE (-700 2700);
FORCEPROP 1 LAST HDL_TAP TRUE
J 0
(-375 2525);
DISPLAY 0.872340 (-375 2525);
DISPLAY INVISIBLE (-375 2525);
FORCEPROP 1 LAST PATH I83
J 0
(-702 2650);
DISPLAY 0.872340 (-702 2650);
PAINT GREEN (-702 2650);
DISPLAY INVISIBLE (-702 2650);
FORCEADD TAP..1
(-700 2750);
FORCEPROP 3 LASTPIN (-750 2750) SIG_NAME M_D_CPU0_SA_DQ<2>
J 0
(-740 2760);
DISPLAY 0.659574 (-740 2760);
PAINT MONO (-740 2760);
DISPLAY INVISIBLE (-740 2760);
FORCEPROP 1 LASTPIN (-750 2750) BN 2
J 0
(-762 2758);
DISPLAY 0.680851 (-762 2758);
PAINT GREEN (-762 2758);
FORCEPROP 2 LAST CDS_LIB standard
J 0
(-700 2750);
PAINT MONO (-700 2750);
DISPLAY INVISIBLE (-700 2750);
FORCEPROP 1 LAST BODY_TYPE PLUMBING
J 0
(-700 2800);
DISPLAY 0.872340 (-700 2800);
PAINT GREEN (-700 2800);
DISPLAY INVISIBLE (-700 2800);
FORCEPROP 1 LAST HDL_TAP TRUE
J 0
(-375 2625);
DISPLAY 0.872340 (-375 2625);
DISPLAY INVISIBLE (-375 2625);
FORCEPROP 1 LAST PATH I84
J 0
(-702 2750);
DISPLAY 0.872340 (-702 2750);
PAINT GREEN (-702 2750);
DISPLAY INVISIBLE (-702 2750);
FORCEADD TAP..1
(-700 2700);
FORCEPROP 3 LASTPIN (-750 2700) SIG_NAME M_D_CPU0_SA_DQ<1>
J 0
(-740 2710);
DISPLAY 0.659574 (-740 2710);
PAINT MONO (-740 2710);
DISPLAY INVISIBLE (-740 2710);
FORCEPROP 1 LASTPIN (-750 2700) BN 1
J 0
(-762 2708);
DISPLAY 0.680851 (-762 2708);
PAINT GREEN (-762 2708);
FORCEPROP 2 LAST CDS_LIB standard
J 0
(-700 2700);
PAINT MONO (-700 2700);
DISPLAY INVISIBLE (-700 2700);
FORCEPROP 1 LAST BODY_TYPE PLUMBING
J 0
(-700 2750);
DISPLAY 0.872340 (-700 2750);
PAINT GREEN (-700 2750);
DISPLAY INVISIBLE (-700 2750);
FORCEPROP 1 LAST HDL_TAP TRUE
J 0
(-375 2575);
DISPLAY 0.872340 (-375 2575);
DISPLAY INVISIBLE (-375 2575);
FORCEPROP 1 LAST PATH I85
J 0
(-702 2700);
DISPLAY 0.872340 (-702 2700);
PAINT GREEN (-702 2700);
DISPLAY INVISIBLE (-702 2700);
FORCEADD TAP..1
(-700 2800);
FORCEPROP 3 LASTPIN (-750 2800) SIG_NAME M_D_CPU0_SA_DQ<3>
J 0
(-740 2810);
DISPLAY 0.659574 (-740 2810);
PAINT MONO (-740 2810);
DISPLAY INVISIBLE (-740 2810);
FORCEPROP 1 LASTPIN (-750 2800) BN 3
J 0
(-762 2808);
DISPLAY 0.680851 (-762 2808);
PAINT GREEN (-762 2808);
FORCEPROP 2 LAST CDS_LIB standard
J 0
(-700 2800);
PAINT MONO (-700 2800);
DISPLAY INVISIBLE (-700 2800);
FORCEPROP 1 LAST BODY_TYPE PLUMBING
J 0
(-700 2850);
DISPLAY 0.872340 (-700 2850);
PAINT GREEN (-700 2850);
DISPLAY INVISIBLE (-700 2850);
FORCEPROP 1 LAST HDL_TAP TRUE
J 0
(-375 2675);
DISPLAY 0.872340 (-375 2675);
DISPLAY INVISIBLE (-375 2675);
FORCEPROP 1 LAST PATH I86
J 0
(-702 2800);
DISPLAY 0.872340 (-702 2800);
PAINT GREEN (-702 2800);
DISPLAY INVISIBLE (-702 2800);
FORCEADD TAP..1
(-700 2850);
FORCEPROP 3 LASTPIN (-750 2850) SIG_NAME M_D_CPU0_SA_DQ<4>
J 0
(-740 2860);
DISPLAY 0.659574 (-740 2860);
PAINT MONO (-740 2860);
DISPLAY INVISIBLE (-740 2860);
FORCEPROP 1 LASTPIN (-750 2850) BN 4
J 0
(-762 2858);
DISPLAY 0.680851 (-762 2858);
PAINT GREEN (-762 2858);
FORCEPROP 2 LAST CDS_LIB standard
J 0
(-700 2850);
PAINT MONO (-700 2850);
DISPLAY INVISIBLE (-700 2850);
FORCEPROP 1 LAST BODY_TYPE PLUMBING
J 0
(-700 2900);
DISPLAY 0.872340 (-700 2900);
PAINT GREEN (-700 2900);
DISPLAY INVISIBLE (-700 2900);
FORCEPROP 1 LAST HDL_TAP TRUE
J 0
(-375 2725);
DISPLAY 0.872340 (-375 2725);
DISPLAY INVISIBLE (-375 2725);
FORCEPROP 1 LAST PATH I87
J 0
(-702 2850);
DISPLAY 0.872340 (-702 2850);
PAINT GREEN (-702 2850);
DISPLAY INVISIBLE (-702 2850);
FORCEADD TAP..1
(-700 2900);
FORCEPROP 3 LASTPIN (-750 2900) SIG_NAME M_D_CPU0_SA_DQ<5>
J 0
(-740 2910);
DISPLAY 0.659574 (-740 2910);
PAINT MONO (-740 2910);
DISPLAY INVISIBLE (-740 2910);
FORCEPROP 1 LASTPIN (-750 2900) BN 5
J 0
(-762 2908);
DISPLAY 0.680851 (-762 2908);
PAINT GREEN (-762 2908);
FORCEPROP 2 LAST CDS_LIB standard
J 0
(-700 2900);
PAINT MONO (-700 2900);
DISPLAY INVISIBLE (-700 2900);
FORCEPROP 1 LAST BODY_TYPE PLUMBING
J 0
(-700 2950);
DISPLAY 0.872340 (-700 2950);
PAINT GREEN (-700 2950);
DISPLAY INVISIBLE (-700 2950);
FORCEPROP 1 LAST HDL_TAP TRUE
J 0
(-375 2775);
DISPLAY 0.872340 (-375 2775);
DISPLAY INVISIBLE (-375 2775);
FORCEPROP 1 LAST PATH I88
J 0
(-702 2900);
DISPLAY 0.872340 (-702 2900);
PAINT GREEN (-702 2900);
DISPLAY INVISIBLE (-702 2900);
FORCEADD TAP..1
(-700 3000);
FORCEPROP 3 LASTPIN (-750 3000) SIG_NAME M_D_CPU0_SA_DQ<7>
J 0
(-740 3010);
DISPLAY 0.659574 (-740 3010);
PAINT MONO (-740 3010);
DISPLAY INVISIBLE (-740 3010);
FORCEPROP 1 LASTPIN (-750 3000) BN 7
J 0
(-762 3008);
DISPLAY 0.680851 (-762 3008);
PAINT GREEN (-762 3008);
FORCEPROP 2 LAST CDS_LIB standard
J 0
(-700 3000);
PAINT MONO (-700 3000);
DISPLAY INVISIBLE (-700 3000);
FORCEPROP 1 LAST BODY_TYPE PLUMBING
J 0
(-700 3050);
DISPLAY 0.872340 (-700 3050);
PAINT GREEN (-700 3050);
DISPLAY INVISIBLE (-700 3050);
FORCEPROP 1 LAST HDL_TAP TRUE
J 0
(-375 2875);
DISPLAY 0.872340 (-375 2875);
DISPLAY INVISIBLE (-375 2875);
FORCEPROP 1 LAST PATH I89
J 0
(-702 3000);
DISPLAY 0.872340 (-702 3000);
PAINT GREEN (-702 3000);
DISPLAY INVISIBLE (-702 3000);
FORCEADD OFFPAGE..1
(-3275 1850);
FORCEPROP 2 LAST $XR1 88 
J 0
(-3586 1850);
DISPLAY 0.638298 (-3586 1850);
PAINT MONO (-3586 1850);
FORCEPROP 2 LAST $XR0 23 
J 0
(-3496 1850);
DISPLAY 0.638298 (-3496 1850);
PAINT MONO (-3496 1850);
FORCEPROP 2 LAST CDS_LIB standard
J 0
(-3275 1850);
PAINT MONO (-3275 1850);
DISPLAY INVISIBLE (-3275 1850);
FORCEPROP 1 LAST OFFPAGE TRUE
J 0
(-2950 1725);
DISPLAY 0.872340 (-2950 1725);
DISPLAY INVISIBLE (-2950 1725);
FORCEPROP 1 LAST COMMENT_BODY TRUE
J 0
(-3150 1750);
DISPLAY 0.872340 (-3150 1750);
PAINT GREEN (-3150 1750);
DISPLAY INVISIBLE (-3150 1750);
FORCEPROP 2 LAST PATH I9
J 0
(-3225 1925);
DISPLAY 1.021277 (-3225 1925);
DISPLAY INVISIBLE (-3225 1925);
FORCEADD TAP..1
(-700 2950);
FORCEPROP 3 LASTPIN (-750 2950) SIG_NAME M_D_CPU0_SA_DQ<6>
J 0
(-740 2960);
DISPLAY 0.659574 (-740 2960);
PAINT MONO (-740 2960);
DISPLAY INVISIBLE (-740 2960);
FORCEPROP 1 LASTPIN (-750 2950) BN 6
J 0
(-762 2958);
DISPLAY 0.680851 (-762 2958);
PAINT GREEN (-762 2958);
FORCEPROP 2 LAST CDS_LIB standard
J 0
(-700 2950);
PAINT MONO (-700 2950);
DISPLAY INVISIBLE (-700 2950);
FORCEPROP 1 LAST BODY_TYPE PLUMBING
J 0
(-700 3000);
DISPLAY 0.872340 (-700 3000);
PAINT GREEN (-700 3000);
DISPLAY INVISIBLE (-700 3000);
FORCEPROP 1 LAST HDL_TAP TRUE
J 0
(-375 2825);
DISPLAY 0.872340 (-375 2825);
DISPLAY INVISIBLE (-375 2825);
FORCEPROP 1 LAST PATH I90
J 0
(-702 2950);
DISPLAY 0.872340 (-702 2950);
PAINT GREEN (-702 2950);
DISPLAY INVISIBLE (-702 2950);
FORCEADD TAP..1
(-700 3050);
FORCEPROP 3 LASTPIN (-750 3050) SIG_NAME M_D_CPU0_SA_DQ<8>
J 0
(-740 3060);
DISPLAY 0.659574 (-740 3060);
PAINT MONO (-740 3060);
DISPLAY INVISIBLE (-740 3060);
FORCEPROP 1 LASTPIN (-750 3050) BN 8
J 0
(-762 3058);
DISPLAY 0.680851 (-762 3058);
PAINT GREEN (-762 3058);
FORCEPROP 2 LAST CDS_LIB standard
J 0
(-700 3050);
PAINT MONO (-700 3050);
DISPLAY INVISIBLE (-700 3050);
FORCEPROP 1 LAST BODY_TYPE PLUMBING
J 0
(-700 3100);
DISPLAY 0.872340 (-700 3100);
PAINT GREEN (-700 3100);
DISPLAY INVISIBLE (-700 3100);
FORCEPROP 1 LAST HDL_TAP TRUE
J 0
(-375 2925);
DISPLAY 0.872340 (-375 2925);
DISPLAY INVISIBLE (-375 2925);
FORCEPROP 1 LAST PATH I91
J 0
(-702 3050);
DISPLAY 0.872340 (-702 3050);
PAINT GREEN (-702 3050);
DISPLAY INVISIBLE (-702 3050);
FORCEADD TAP..1
(-700 3100);
FORCEPROP 3 LASTPIN (-750 3100) SIG_NAME M_D_CPU0_SA_DQ<9>
J 0
(-740 3110);
DISPLAY 0.659574 (-740 3110);
PAINT MONO (-740 3110);
DISPLAY INVISIBLE (-740 3110);
FORCEPROP 1 LASTPIN (-750 3100) BN 9
J 0
(-762 3108);
DISPLAY 0.680851 (-762 3108);
PAINT GREEN (-762 3108);
FORCEPROP 2 LAST CDS_LIB standard
J 0
(-700 3100);
PAINT MONO (-700 3100);
DISPLAY INVISIBLE (-700 3100);
FORCEPROP 1 LAST BODY_TYPE PLUMBING
J 0
(-700 3150);
DISPLAY 0.872340 (-700 3150);
PAINT GREEN (-700 3150);
DISPLAY INVISIBLE (-700 3150);
FORCEPROP 1 LAST HDL_TAP TRUE
J 0
(-375 2975);
DISPLAY 0.872340 (-375 2975);
DISPLAY INVISIBLE (-375 2975);
FORCEPROP 1 LAST PATH I92
J 0
(-702 3100);
DISPLAY 0.872340 (-702 3100);
PAINT GREEN (-702 3100);
DISPLAY INVISIBLE (-702 3100);
FORCEADD TAP..1
(-700 3150);
FORCEPROP 3 LASTPIN (-750 3150) SIG_NAME M_D_CPU0_SA_DQ<10>
J 0
(-740 3160);
DISPLAY 0.659574 (-740 3160);
PAINT MONO (-740 3160);
DISPLAY INVISIBLE (-740 3160);
FORCEPROP 1 LASTPIN (-750 3150) BN 10
J 0
(-762 3158);
DISPLAY 0.680851 (-762 3158);
PAINT GREEN (-762 3158);
FORCEPROP 2 LAST CDS_LIB standard
J 0
(-700 3150);
PAINT MONO (-700 3150);
DISPLAY INVISIBLE (-700 3150);
FORCEPROP 1 LAST BODY_TYPE PLUMBING
J 0
(-700 3200);
DISPLAY 0.872340 (-700 3200);
PAINT GREEN (-700 3200);
DISPLAY INVISIBLE (-700 3200);
FORCEPROP 1 LAST HDL_TAP TRUE
J 0
(-375 3025);
DISPLAY 0.872340 (-375 3025);
DISPLAY INVISIBLE (-375 3025);
FORCEPROP 1 LAST PATH I93
J 0
(-702 3150);
DISPLAY 0.872340 (-702 3150);
PAINT GREEN (-702 3150);
DISPLAY INVISIBLE (-702 3150);
FORCEADD TAP..1
(-700 3200);
FORCEPROP 3 LASTPIN (-750 3200) SIG_NAME M_D_CPU0_SA_DQ<11>
J 0
(-740 3210);
DISPLAY 0.659574 (-740 3210);
PAINT MONO (-740 3210);
DISPLAY INVISIBLE (-740 3210);
FORCEPROP 1 LASTPIN (-750 3200) BN 11
J 0
(-762 3208);
DISPLAY 0.680851 (-762 3208);
PAINT GREEN (-762 3208);
FORCEPROP 2 LAST CDS_LIB standard
J 0
(-700 3200);
PAINT MONO (-700 3200);
DISPLAY INVISIBLE (-700 3200);
FORCEPROP 1 LAST BODY_TYPE PLUMBING
J 0
(-700 3250);
DISPLAY 0.872340 (-700 3250);
PAINT GREEN (-700 3250);
DISPLAY INVISIBLE (-700 3250);
FORCEPROP 1 LAST HDL_TAP TRUE
J 0
(-375 3075);
DISPLAY 0.872340 (-375 3075);
DISPLAY INVISIBLE (-375 3075);
FORCEPROP 1 LAST PATH I94
J 0
(-702 3200);
DISPLAY 0.872340 (-702 3200);
PAINT GREEN (-702 3200);
DISPLAY INVISIBLE (-702 3200);
FORCEADD TAP..1
(-700 3250);
FORCEPROP 3 LASTPIN (-750 3250) SIG_NAME M_D_CPU0_SA_DQ<12>
J 0
(-740 3260);
DISPLAY 0.659574 (-740 3260);
PAINT MONO (-740 3260);
DISPLAY INVISIBLE (-740 3260);
FORCEPROP 1 LASTPIN (-750 3250) BN 12
J 0
(-762 3258);
DISPLAY 0.680851 (-762 3258);
PAINT GREEN (-762 3258);
FORCEPROP 2 LAST CDS_LIB standard
J 0
(-700 3250);
PAINT MONO (-700 3250);
DISPLAY INVISIBLE (-700 3250);
FORCEPROP 1 LAST BODY_TYPE PLUMBING
J 0
(-700 3300);
DISPLAY 0.872340 (-700 3300);
PAINT GREEN (-700 3300);
DISPLAY INVISIBLE (-700 3300);
FORCEPROP 1 LAST HDL_TAP TRUE
J 0
(-375 3125);
DISPLAY 0.872340 (-375 3125);
DISPLAY INVISIBLE (-375 3125);
FORCEPROP 1 LAST PATH I95
J 0
(-702 3250);
DISPLAY 0.872340 (-702 3250);
PAINT GREEN (-702 3250);
DISPLAY INVISIBLE (-702 3250);
FORCEADD TAP..1
(-700 3300);
FORCEPROP 3 LASTPIN (-750 3300) SIG_NAME M_D_CPU0_SA_DQ<13>
J 0
(-740 3310);
DISPLAY 0.659574 (-740 3310);
PAINT MONO (-740 3310);
DISPLAY INVISIBLE (-740 3310);
FORCEPROP 1 LASTPIN (-750 3300) BN 13
J 0
(-762 3308);
DISPLAY 0.680851 (-762 3308);
PAINT GREEN (-762 3308);
FORCEPROP 2 LAST CDS_LIB standard
J 0
(-700 3300);
PAINT MONO (-700 3300);
DISPLAY INVISIBLE (-700 3300);
FORCEPROP 1 LAST BODY_TYPE PLUMBING
J 0
(-700 3350);
DISPLAY 0.872340 (-700 3350);
PAINT GREEN (-700 3350);
DISPLAY INVISIBLE (-700 3350);
FORCEPROP 1 LAST HDL_TAP TRUE
J 0
(-375 3175);
DISPLAY 0.872340 (-375 3175);
DISPLAY INVISIBLE (-375 3175);
FORCEPROP 1 LAST PATH I96
J 0
(-702 3300);
DISPLAY 0.872340 (-702 3300);
PAINT GREEN (-702 3300);
DISPLAY INVISIBLE (-702 3300);
FORCEADD TAP..1
(-700 3350);
FORCEPROP 3 LASTPIN (-750 3350) SIG_NAME M_D_CPU0_SA_DQ<14>
J 0
(-740 3360);
DISPLAY 0.659574 (-740 3360);
PAINT MONO (-740 3360);
DISPLAY INVISIBLE (-740 3360);
FORCEPROP 1 LASTPIN (-750 3350) BN 14
J 0
(-762 3358);
DISPLAY 0.680851 (-762 3358);
PAINT GREEN (-762 3358);
FORCEPROP 2 LAST CDS_LIB standard
J 0
(-700 3350);
PAINT MONO (-700 3350);
DISPLAY INVISIBLE (-700 3350);
FORCEPROP 1 LAST BODY_TYPE PLUMBING
J 0
(-700 3400);
DISPLAY 0.872340 (-700 3400);
PAINT GREEN (-700 3400);
DISPLAY INVISIBLE (-700 3400);
FORCEPROP 1 LAST HDL_TAP TRUE
J 0
(-375 3225);
DISPLAY 0.872340 (-375 3225);
DISPLAY INVISIBLE (-375 3225);
FORCEPROP 1 LAST PATH I97
J 0
(-702 3350);
DISPLAY 0.872340 (-702 3350);
PAINT GREEN (-702 3350);
DISPLAY INVISIBLE (-702 3350);
FORCEADD TAP..1
(-700 3450);
FORCEPROP 3 LASTPIN (-750 3450) SIG_NAME M_D_CPU0_SA_DQ<16>
J 0
(-740 3460);
DISPLAY 0.659574 (-740 3460);
PAINT MONO (-740 3460);
DISPLAY INVISIBLE (-740 3460);
FORCEPROP 1 LASTPIN (-750 3450) BN 16
J 0
(-762 3458);
DISPLAY 0.680851 (-762 3458);
PAINT GREEN (-762 3458);
FORCEPROP 2 LAST CDS_LIB standard
J 0
(-700 3450);
PAINT MONO (-700 3450);
DISPLAY INVISIBLE (-700 3450);
FORCEPROP 1 LAST BODY_TYPE PLUMBING
J 0
(-700 3500);
DISPLAY 0.872340 (-700 3500);
PAINT GREEN (-700 3500);
DISPLAY INVISIBLE (-700 3500);
FORCEPROP 1 LAST HDL_TAP TRUE
J 0
(-375 3325);
DISPLAY 0.872340 (-375 3325);
DISPLAY INVISIBLE (-375 3325);
FORCEPROP 1 LAST PATH I98
J 0
(-702 3450);
DISPLAY 0.872340 (-702 3450);
PAINT GREEN (-702 3450);
DISPLAY INVISIBLE (-702 3450);
FORCEADD TAP..1
(-700 3400);
FORCEPROP 3 LASTPIN (-750 3400) SIG_NAME M_D_CPU0_SA_DQ<15>
J 0
(-740 3410);
DISPLAY 0.659574 (-740 3410);
PAINT MONO (-740 3410);
DISPLAY INVISIBLE (-740 3410);
FORCEPROP 1 LASTPIN (-750 3400) BN 15
J 0
(-762 3408);
DISPLAY 0.680851 (-762 3408);
PAINT GREEN (-762 3408);
FORCEPROP 2 LAST CDS_LIB standard
J 0
(-700 3400);
PAINT MONO (-700 3400);
DISPLAY INVISIBLE (-700 3400);
FORCEPROP 1 LAST BODY_TYPE PLUMBING
J 0
(-700 3450);
DISPLAY 0.872340 (-700 3450);
PAINT GREEN (-700 3450);
DISPLAY INVISIBLE (-700 3450);
FORCEPROP 1 LAST HDL_TAP TRUE
J 0
(-375 3275);
DISPLAY 0.872340 (-375 3275);
DISPLAY INVISIBLE (-375 3275);
FORCEPROP 1 LAST PATH I99
J 0
(-702 3400);
DISPLAY 0.872340 (-702 3400);
PAINT GREEN (-702 3400);
DISPLAY INVISIBLE (-702 3400);
FORCEADD CAD_NOTE..1
(1150 -250);
FORCEPROP 0 LAST S1 PLACE THE BYPASS CAPS CLOSE TO DIMM
J 0
(1025 -375);
DISPLAY 1.021277 (1025 -375);
PAINT WHITE (1025 -375);
FORCEPROP 2 LAST CDS_LIB logical_power
J 0
(1150 -250);
PAINT MONO (1150 -250);
DISPLAY INVISIBLE (1150 -250);
FORCEPROP 1 LAST COMMENT_BODY TRUE
J 0
(1175 -150);
DISPLAY 0.978723 (1175 -150);
DISPLAY INVISIBLE (1175 -150);
FORCEADD QUANTA_TITLE_BLOCK_C..1
(5625 -1550);
FORCEPROP 0 LAST CDS_CON_LAST_MODIFIED Fri Aug 25 14:01:08 2023
J 0
(3740 -1535);
PAINT MONO (3740 -1535);
DISPLAY INVISIBLE (3740 -1535);
FORCEPROP 1 LAST CUSTOM_TXT_CDS <CON_LAST_MODIFIED>
J 0
(3740 -1535);
DISPLAY 0.978723 (3740 -1535);
FORCEPROP 2 LAST CUSTOM_TXT_CDS <XR_PAGE_TITLE>
J 0
(-2265 3700);
DISPLAY 0.638298 (-2265 3700);
PAINT PINK (-2265 3700);
DISPLAY INVISIBLE (-2265 3700);
FORCEPROP 2 LAST CUSTOM_TXT_CDS <Q_NUMBER>
J 0
(4222 -1447);
DISPLAY 1.212766 (4222 -1447);
FORCEPROP 1 LAST CUSTOM_TXT_CDS <NAME_2>
J 0
(2450 -1500);
FORCEPROP 1 LAST CUSTOM_TXT_CDS <NAME_1>
J 0
(2450 -1375);
FORCEPROP 1 LAST CUSTOM_TXT_CDS <Q_PROJ>
J 0
(3243 -1448);
DISPLAY 1.212766 (3243 -1448);
FORCEPROP 1 LAST CUSTOM_TXT_CDS <Q_REV>
J 0
(5441 -1447);
DISPLAY 1.212766 (5441 -1447);
FORCEPROP 1 LAST CUSTOM_TXT_CDS <CON_PAGE_NUM> OF <CON_TOTAL_PAGES>
J 0
(5179 -1532);
DISPLAY 0.978723 (5179 -1532);
FORCEPROP 1 LAST Q_TITLE DDR5 - CPU0 CHD DIMM2(BLACK)
J 0
(-3741 -1524);
DISPLAY 2.446809 (-3741 -1524);
PAINT GREEN (-3741 -1524);
FORCEPROP 1 LAST Q_DEPT 
J 1
(1862 -1501);
DISPLAY 1.957447 (1862 -1501);
PAINT GREEN (1862 -1501);
FORCEPROP 1 LAST COMMENT_BODY TRUE
J 0
(5637 -1563);
DISPLAY 0.978723 (5637 -1563);
PAINT GREEN (5637 -1563);
DISPLAY INVISIBLE (5637 -1563);
FORCEPROP 2 LAST CDS_XR_PAGE_TITLE CR-89 : @S9S_MB_2U_LIB.S9S_MB_2U(SCH_1):PAGE89
J 0
(-2265 3700);
DISPLAY 0.638298 (-2265 3700);
PAINT PINK (-2265 3700);
DISPLAY INVISIBLE (-2265 3700);
FORCEPROP 2 LAST PAGE_BORDER TRUE
J 0
(-2265 3700);
DISPLAY 0.638298 (-2265 3700);
PAINT PINK (-2265 3700);
DISPLAY INVISIBLE (-2265 3700);
FORCEPROP 1 LAST CDS_LMAN_SYM_OUTLINE -9475,6775,100,-125
J 0
(5625 -1550);
DISPLAY 0.468085 (5625 -1550);
PAINT GREEN (5625 -1550);
DISPLAY INVISIBLE (5625 -1550);
FORCEPROP 2 LAST CDS_LIB pure_quanta
J 0
(5625 -1550);
PAINT MONO (5625 -1550);
DISPLAY INVISIBLE (5625 -1550);
WIRE 17 -1 (-2400 2125)(-2400 2175);
WIRE 17 -1 (-2400 2075)(-2400 2125);
WIRE 17 -1 (-2400 2175)(-2400 2225);
WIRE 17 -1 (-2400 2225)(-2400 2275);
WIRE 17 -1 (-2400 2025)(-2400 2075);
WIRE 17 -1 (-2400 2275)(-2400 2325);
WIRE 17 -1 (-2400 2325)(-2400 2375);
WIRE 17 -1 (-3225 2375)(-2400 2375);
FORCEPROP 2 LAST SIG_NAME M_D_CPU0_SB_CB<7:0>
J 0
(-3135 2385);
DISPLAY 0.680851 (-3135 2385);
PAINT WHITE (-3135 2385);
WIRE 17 -1 (-2400 2725)(-2400 2775);
WIRE 17 -1 (-2400 2675)(-2400 2725);
WIRE 17 -1 (-2400 2775)(-2400 2825);
WIRE 17 -1 (-3225 2825)(-2400 2825);
FORCEPROP 2 LAST SIG_NAME M_D_CPU0_SA_CB<7:0>
J 0
(-3135 2835);
DISPLAY 0.680851 (-3135 2835);
PAINT WHITE (-3135 2835);
WIRE 17 -1 (-3225 4225)(-2400 4225);
FORCEPROP 2 LAST SIG_NAME M_D_CPU0_SA_CA<6:0>
J 0
(-3135 4235);
DISPLAY 0.680851 (-3135 4235);
PAINT WHITE (-3135 4235);
WIRE 17 -1 (-2400 4175)(-2400 4225);
WIRE 17 -1 (-2400 4125)(-2400 4175);
WIRE 17 -1 (-2400 4075)(-2400 4125);
WIRE 17 -1 (-650 3375)(-650 3425);
WIRE 17 -1 (-650 3325)(-650 3375);
WIRE 17 -1 (-650 3425)(-650 3475);
WIRE 17 -1 (-650 3475)(-650 3525);
WIRE 17 -1 (-650 3275)(-650 3325);
WIRE 17 -1 (-650 3225)(-650 3275);
WIRE 17 -1 (-650 3525)(-650 3575);
WIRE 17 -1 (-650 3575)(-650 3625);
WIRE 17 -1 (-650 3175)(-650 3225);
WIRE 17 -1 (-650 3125)(-650 3175);
WIRE 17 -1 (-650 3625)(-650 3675);
WIRE 17 -1 (-650 3675)(-650 3725);
WIRE 17 -1 (-650 3075)(-650 3125);
WIRE 17 -1 (-650 3025)(-650 3075);
WIRE 17 -1 (-650 3725)(-650 3775);
WIRE 17 -1 (-650 3775)(-650 3825);
WIRE 17 -1 (-650 2975)(-650 3025);
WIRE 17 -1 (-650 2925)(-650 2975);
WIRE 17 -1 (-650 3825)(-650 3875);
WIRE 17 -1 (-650 3875)(-650 3925);
WIRE 17 -1 (-650 2875)(-650 2925);
WIRE 17 -1 (-650 2825)(-650 2875);
WIRE 17 -1 (-650 3925)(-650 3975);
WIRE 17 -1 (-650 3975)(-650 4025);
WIRE 17 -1 (-650 2775)(-650 2825);
WIRE 17 -1 (-650 2725)(-650 2775);
WIRE 17 -1 (-650 4025)(-650 4075);
WIRE 17 -1 (-650 4075)(-650 4125);
WIRE 17 -1 (-650 2675)(-650 2725);
WIRE 17 -1 (-650 4125)(-650 4175);
WIRE 17 -1 (-650 4175)(-650 4225);
WIRE 17 -1 (-650 4225)(75 4225);
FORCEPROP 2 LAST SIG_NAME M_D_CPU0_SA_DQ<31:0>
J 0
(-585 4235);
DISPLAY 0.680851 (-585 4235);
PAINT WHITE (-585 4235);
WIRE 17 -1 (-650 1575)(-650 1625);
WIRE 17 -1 (-650 1525)(-650 1575);
WIRE 17 -1 (-650 1625)(-650 1675);
WIRE 17 -1 (-650 1675)(-650 1725);
WIRE 17 -1 (-650 1475)(-650 1525);
WIRE 17 -1 (-650 1425)(-650 1475);
WIRE 17 -1 (-650 1725)(-650 1775);
WIRE 17 -1 (-650 1775)(-650 1825);
WIRE 17 -1 (-650 1375)(-650 1425);
WIRE 17 -1 (-650 1325)(-650 1375);
WIRE 17 -1 (-650 1825)(-650 1875);
WIRE 17 -1 (-650 1875)(-650 1925);
WIRE 17 -1 (-650 1275)(-650 1325);
WIRE 17 -1 (-650 1225)(-650 1275);
WIRE 17 -1 (-650 1925)(-650 1975);
WIRE 17 -1 (-650 1975)(-650 2025);
WIRE 17 -1 (-650 1175)(-650 1225);
WIRE 17 -1 (-650 1125)(-650 1175);
WIRE 17 -1 (-650 2025)(-650 2075);
WIRE 17 -1 (-650 2075)(-650 2125);
WIRE 17 -1 (-650 1075)(-650 1125);
WIRE 17 -1 (-650 1025)(-650 1075);
WIRE 17 -1 (-650 2125)(-650 2175);
WIRE 17 -1 (-650 2175)(-650 2225);
WIRE 17 -1 (-650 2225)(-650 2275);
WIRE 17 -1 (-650 2275)(-650 2325);
WIRE 17 -1 (-650 2325)(-650 2375);
WIRE 17 -1 (-650 2375)(-650 2425);
WIRE 17 -1 (-650 2425)(-650 2475);
WIRE 17 -1 (-650 2475)(-650 2525);
WIRE 17 -1 (-650 2525)(-650 2575);
WIRE 17 -1 (-650 2575)(75 2575);
FORCEPROP 2 LAST SIG_NAME M_D_CPU0_SB_DQ<31:0>
J 0
(-585 2585);
DISPLAY 0.680851 (-585 2585);
PAINT WHITE (-585 2585);
WIRE 17 -1 (-2400 2575)(-2400 2625);
WIRE 17 -1 (-2400 2525)(-2400 2575);
WIRE 17 -1 (-2400 2625)(-2400 2675);
WIRE 17 -1 (-2400 2475)(-2400 2525);
WIRE 17 -1 (-3225 3825)(-2400 3825);
FORCEPROP 2 LAST SIG_NAME M_D_CPU0_SB_CA<6:0>
J 0
(-3135 3835);
DISPLAY 0.680851 (-3135 3835);
PAINT WHITE (-3135 3835);
WIRE 17 -1 (-2400 3775)(-2400 3825);
WIRE 17 -1 (-2400 3725)(-2400 3775);
WIRE 17 -1 (-2400 3675)(-2400 3725);
WIRE 17 -1 (-2400 3625)(-2400 3675);
WIRE 17 -1 (-2400 3575)(-2400 3625);
WIRE 17 -1 (-2400 3525)(-2400 3575);
WIRE 17 -1 (-2400 4025)(-2400 4075);
WIRE 17 -1 (-2400 3975)(-2400 4025);
WIRE 17 -1 (-2400 3925)(-2400 3975);
WIRE 17 -1 (2100 4025)(2100 4125);
WIRE 17 -1 (2100 3925)(2100 4025);
WIRE 17 -1 (2100 4125)(2100 4225);
WIRE 17 -1 (2100 4225)(3125 4225);
FORCEPROP 2 LAST SIG_NAME M_D_CPU0_SA_DQS_DP<9:0>
J 0
(2340 4235);
DISPLAY 0.680851 (2340 4235);
PAINT WHITE (2340 4235);
WIRE 17 -1 (2100 3825)(2100 3925);
WIRE 17 -1 (2100 3725)(2100 3825);
WIRE 17 -1 (2100 3725)(2100 3625);
WIRE 17 -1 (2100 3525)(2100 3625);
WIRE 17 -1 (2100 3425)(2100 3525);
WIRE 17 -1 (2100 3325)(2100 3425);
WIRE 17 -1 (2100 3175)(3125 3175);
FORCEPROP 2 LAST SIG_NAME M_D_CPU0_SB_DQS_DP<9:0>
J 0
(2340 3185);
DISPLAY 0.680851 (2340 3185);
PAINT WHITE (2340 3185);
WIRE 17 -1 (2100 3075)(2100 3175);
WIRE 17 -1 (2100 2975)(2100 3075);
WIRE 17 -1 (2100 2875)(2100 2975);
WIRE 17 -1 (2100 2775)(2100 2875);
WIRE 17 -1 (2100 2675)(2100 2775);
WIRE 17 -1 (2100 2675)(2100 2575);
WIRE 17 -1 (2100 2475)(2100 2575);
WIRE 17 -1 (2100 2375)(2100 2475);
WIRE 17 -1 (2100 2275)(2100 2375);
WIRE 17 -1 (2275 2325)(2275 2425);
WIRE 17 -1 (2275 2225)(2275 2325);
WIRE 17 -1 (2275 2425)(2275 2525);
WIRE 17 -1 (2275 2625)(2275 2525);
WIRE 17 -1 (2275 2625)(2275 2725);
WIRE 17 -1 (2275 2725)(2275 2825);
WIRE 17 -1 (2275 2825)(2275 2925);
WIRE 17 -1 (2275 2925)(2275 3025);
WIRE 17 -1 (2275 3025)(2275 3125);
WIRE 17 -1 (2275 3125)(3125 3125);
FORCEPROP 2 LAST SIG_NAME M_D_CPU0_SB_DQS_DN<9:0>
J 0
(2340 3135);
DISPLAY 0.680851 (2340 3135);
PAINT WHITE (2340 3135);
WIRE 17 -1 (2275 3275)(2275 3375);
WIRE 17 -1 (2275 3375)(2275 3475);
WIRE 17 -1 (2275 3475)(2275 3575);
WIRE 17 -1 (2275 3675)(2275 3575);
WIRE 17 -1 (2275 3675)(2275 3775);
WIRE 17 -1 (2275 3775)(2275 3875);
WIRE 17 -1 (2275 3875)(2275 3975);
WIRE 17 -1 (2275 3975)(2275 4075);
WIRE 17 -1 (2275 4075)(2275 4175);
WIRE 17 -1 (2275 4175)(3125 4175);
FORCEPROP 2 LAST SIG_NAME M_D_CPU0_SA_DQS_DN<9:0>
J 0
(2340 4185);
DISPLAY 0.680851 (2340 4185);
PAINT WHITE (2340 4185);
WIRE 16 -1 (-3175 2025)(-3175 1750);
WIRE 16 -1 (1025 425)(1025 600);
WIRE 16 -1 (2025 600)(2025 550);
WIRE 16 -1 (3725 4700)(3725 4200);
WIRE 16 -1 (-2125 -125)(-2125 -50);
WIRE 16 -1 (1025 225)(1025 0);
WIRE 16 -1 (2650 0)(2650 75);
WIRE 16 -1 (3725 550)(3725 950);
WIRE 16 -1 (5425 850)(5425 550);
WIRE 16 -1 (5425 900)(5425 850);
WIRE 16 -1 (5175 850)(5425 850);
WIRE 16 3135 (675 825)(675 -475);
WIRE 16 3135 (3275 825)(675 825);
WIRE 16 3135 (675 -475)(3275 -475);
WIRE 16 3135 (3275 -475)(3275 825);
WIRE 16 -1 (-2125 1650)(-3150 1650);
FORCEPROP 2 LAST SIG_NAME I3C_SPD_DDRABCD_CPU0_LVC1_SDA
J 0
(-3160 1660);
DISPLAY 0.680851 (-3160 1660);
PAINT WHITE (-3160 1660);
WIRE 16 -1 (-2125 1700)(-3150 1700);
FORCEPROP 2 LAST SIG_NAME PD_CHD_CPU0_DIMM2_SAA
J 0
(-3160 1710);
DISPLAY 0.680851 (-3160 1710);
PAINT WHITE (-3160 1710);
WIRE 16 -1 (-3175 1750)(-2125 1750);
WIRE 16 -1 (-2525 1900)(-2125 1900);
WIRE 16 -1 (-2525 1950)(-3250 1950);
FORCEPROP 2 LAST SIG_NAME RST_M_CD_CPU0_FPGA_N
J 0
(-3162 1959);
DISPLAY 0.680851 (-3162 1959);
PAINT WHITE (-3162 1959);
WIRE 16 -1 (-2525 1950)(-2525 1900);
WIRE 16 -1 (-2125 1850)(-3225 1850);
FORCEPROP 2 LAST SIG_NAME M_D_CPU0_ALERT_N
J 0
(-3137 1859);
DISPLAY 0.680851 (-3137 1859);
PAINT WHITE (-3137 1859);
WIRE 16 -1 (-3700 1525)(-3500 1525);
WIRE 16 -1 (-3700 1600)(-3700 1525);
WIRE 16 -1 (-3700 1600)(-2125 1600);
FORCEPROP 2 LAST SIG_NAME I3C_SPD_DDRABCD_CPU0_LVC1_SCL_R8
J 0
(-3185 1610);
DISPLAY 0.680851 (-3185 1610);
PAINT WHITE (-3185 1610);
WIRE 16 -1 (-2050 1450)(-2075 1450);
WIRE 16 -1 (-2050 1525)(-2050 1450);
WIRE 16 -1 (-3300 1525)(-2050 1525);
FORCEPROP 2 LAST SIG_NAME I3C_SPD_DDRABCD_CPU0_LVC1_SCL
J 0
(-3160 1535);
DISPLAY 0.680851 (-3160 1535);
PAINT WHITE (-3160 1535);
WIRE 16 -1 (-2125 1350)(-3225 1350);
FORCEPROP 2 LAST SIG_NAME PWRGD_CHD_CPU0_DIMM2
J 0
(-3137 1359);
DISPLAY 0.680851 (-3137 1359);
PAINT WHITE (-3137 1359);
WIRE 16 -1 (-2125 1250)(-3225 1250);
FORCEPROP 2 LAST SIG_NAME TP_CHD_CPU0_DIMM2_FRU_6
J 0
(-3137 1259);
DISPLAY 0.680851 (-3137 1259);
PAINT WHITE (-3137 1259);
WIRE 16 -1 (-2300 2000)(-2125 2000);
WIRE 16 -1 (-2300 2100)(-2125 2100);
WIRE 16 -1 (-2300 2450)(-2125 2450);
WIRE 16 -1 (1900 4150)(2175 4150);
WIRE 16 -1 (1900 4050)(2175 4050);
WIRE 16 -1 (1900 3850)(2175 3850);
WIRE 16 -1 (1900 3950)(2175 3950);
WIRE 16 -1 (1900 3750)(2175 3750);
WIRE 16 -1 (1900 3650)(2175 3650);
WIRE 16 -1 (1900 3550)(2175 3550);
WIRE 16 -1 (1900 3350)(2175 3350);
WIRE 16 -1 (1900 3450)(2175 3450);
WIRE 16 -1 (1900 3250)(2175 3250);
WIRE 16 -1 (1900 3100)(2175 3100);
WIRE 16 -1 (1900 3000)(2175 3000);
WIRE 16 -1 (1900 2900)(2175 2900);
WIRE 16 -1 (1900 2800)(2175 2800);
WIRE 16 -1 (1900 2700)(2175 2700);
WIRE 16 -1 (1900 2600)(2175 2600);
WIRE 16 -1 (1900 2500)(2175 2500);
WIRE 16 -1 (1900 2400)(2175 2400);
WIRE 16 -1 (1900 2200)(2175 2200);
WIRE 16 -1 (1900 2300)(2175 2300);
WIRE 16 -1 (1900 4200)(2000 4200);
WIRE 16 -1 (1900 4100)(2000 4100);
WIRE 16 -1 (1900 2250)(2000 2250);
WIRE 16 -1 (1900 2350)(2000 2350);
WIRE 16 -1 (1900 2450)(2000 2450);
WIRE 16 -1 (1900 2550)(2000 2550);
WIRE 16 -1 (1900 2650)(2000 2650);
WIRE 16 -1 (1900 2750)(2000 2750);
WIRE 16 -1 (1900 2850)(2000 2850);
WIRE 16 -1 (1900 2950)(2000 2950);
WIRE 16 -1 (1900 3050)(2000 3050);
WIRE 16 -1 (1900 3150)(2000 3150);
WIRE 16 -1 (1900 3300)(2000 3300);
WIRE 16 -1 (1900 3400)(2000 3400);
WIRE 16 -1 (1900 3500)(2000 3500);
WIRE 16 -1 (1900 3600)(2000 3600);
WIRE 16 -1 (1900 3700)(2000 3700);
WIRE 16 -1 (1900 3800)(2000 3800);
WIRE 16 -1 (1900 3900)(2000 3900);
WIRE 16 -1 (1900 4000)(2000 4000);
WIRE 16 -1 (-2125 1200)(-3225 1200);
FORCEPROP 2 LAST SIG_NAME TP_CHD_CPU0_DIMM2_FRU_5
J 0
(-3137 1209);
DISPLAY 0.680851 (-3137 1209);
PAINT WHITE (-3137 1209);
WIRE 16 -1 (2025 550)(2025 425);
WIRE 16 -1 (2650 550)(2025 550);
WIRE 16 -1 (2650 425)(2650 550);
WIRE 16 -1 (2025 75)(2025 225);
WIRE 16 -1 (2650 75)(2025 75);
WIRE 16 -1 (2650 75)(2650 225);
WIRE 16 -1 (-2125 250)(-3225 250);
FORCEPROP 2 LAST SIG_NAME PD_CHD_CPU0_DIMM2_SAA
J 0
(-3137 259);
DISPLAY 0.680851 (-3137 259);
PAINT WHITE (-3137 259);
WIRE 16 -1 (-2125 150)(-2125 250);
WIRE 16 -1 (5175 900)(5425 900);
WIRE 16 -1 (5175 950)(5425 950);
WIRE 16 -1 (5425 950)(5425 900);
WIRE 16 -1 (5425 1050)(5425 950);
WIRE 16 -1 (5175 1050)(5425 1050);
WIRE 16 -1 (5175 1100)(5425 1100);
WIRE 16 -1 (5425 1100)(5425 1050);
WIRE 16 -1 (5175 1150)(5425 1150);
WIRE 16 -1 (5425 1100)(5425 1150);
WIRE 16 -1 (5175 1200)(5425 1200);
WIRE 16 -1 (5425 1200)(5425 1150);
WIRE 16 -1 (5175 1250)(5425 1250);
WIRE 16 -1 (5425 1250)(5425 1200);
WIRE 16 -1 (5175 1300)(5425 1300);
WIRE 16 -1 (5425 1300)(5425 1250);
WIRE 16 -1 (5175 1350)(5425 1350);
WIRE 16 -1 (5425 1350)(5425 1300);
WIRE 16 -1 (5175 1400)(5425 1400);
WIRE 16 -1 (5425 1400)(5425 1350);
WIRE 16 -1 (5175 1450)(5425 1450);
WIRE 16 -1 (5425 1450)(5425 1400);
WIRE 16 -1 (5425 1500)(5175 1500);
WIRE 16 -1 (5425 1500)(5425 1450);
WIRE 16 -1 (5425 1550)(5425 1500);
WIRE 16 -1 (5425 1550)(5175 1550);
WIRE 16 -1 (5425 1600)(5175 1600);
WIRE 16 -1 (5425 1600)(5425 1550);
WIRE 16 -1 (5175 1650)(5425 1650);
WIRE 16 -1 (5425 1600)(5425 1650);
WIRE 16 -1 (5425 1700)(5175 1700);
WIRE 16 -1 (5425 1650)(5425 1700);
WIRE 16 -1 (5425 1750)(5175 1750);
WIRE 16 -1 (5425 1750)(5425 1700);
WIRE 16 -1 (5425 1800)(5175 1800);
WIRE 16 -1 (5425 1800)(5425 1750);
WIRE 16 -1 (5425 1850)(5175 1850);
WIRE 16 -1 (5425 1850)(5425 1800);
WIRE 16 -1 (5175 1900)(5425 1900);
WIRE 16 -1 (5425 1900)(5425 1850);
WIRE 16 -1 (5175 1950)(5425 1950);
WIRE 16 -1 (5425 1950)(5425 1900);
WIRE 16 -1 (5175 2000)(5425 2000);
WIRE 16 -1 (5425 1950)(5425 2000);
WIRE 16 -1 (5425 2050)(5425 2000);
WIRE 16 -1 (5175 2050)(5425 2050);
WIRE 16 -1 (5175 2100)(5425 2100);
WIRE 16 -1 (5425 2100)(5425 2050);
WIRE 16 -1 (5175 2150)(5425 2150);
WIRE 16 -1 (5425 2150)(5425 2100);
WIRE 16 -1 (5175 2200)(5425 2200);
WIRE 16 -1 (5425 2200)(5425 2150);
WIRE 16 -1 (5175 2250)(5425 2250);
WIRE 16 -1 (5425 2250)(5425 2200);
WIRE 16 -1 (5425 2300)(5175 2300);
WIRE 16 -1 (5425 2300)(5425 2250);
WIRE 16 -1 (5425 2350)(5175 2350);
WIRE 16 -1 (5425 2350)(5425 2300);
WIRE 16 -1 (5175 2400)(5425 2400);
WIRE 16 -1 (5425 2400)(5425 2350);
WIRE 16 -1 (5175 2450)(5425 2450);
WIRE 16 -1 (5425 2450)(5425 2400);
WIRE 16 -1 (5175 2500)(5425 2500);
WIRE 16 -1 (5425 2450)(5425 2500);
WIRE 16 -1 (5175 2550)(5425 2550);
WIRE 16 -1 (5425 2550)(5425 2500);
WIRE 16 -1 (5425 2600)(5425 2550);
WIRE 16 -1 (5175 2600)(5425 2600);
WIRE 16 -1 (5175 2650)(5425 2650);
WIRE 16 -1 (5425 2650)(5425 2600);
WIRE 16 -1 (5175 2700)(5425 2700);
WIRE 16 -1 (5425 2700)(5425 2650);
WIRE 16 -1 (5175 2750)(5425 2750);
WIRE 16 -1 (5425 2750)(5425 2700);
WIRE 16 -1 (5425 2800)(5175 2800);
WIRE 16 -1 (5425 2800)(5425 2750);
WIRE 16 -1 (5425 2850)(5175 2850);
WIRE 16 -1 (5425 2850)(5425 2800);
WIRE 16 -1 (5175 2900)(5425 2900);
WIRE 16 -1 (5425 2900)(5425 2850);
WIRE 16 -1 (5175 2950)(5425 2950);
WIRE 16 -1 (5425 2950)(5425 2900);
WIRE 16 -1 (5175 3000)(5425 3000);
WIRE 16 -1 (5425 2950)(5425 3000);
WIRE 16 -1 (5175 3050)(5425 3050);
WIRE 16 -1 (5425 3050)(5425 3000);
WIRE 16 -1 (5425 3100)(5425 3050);
WIRE 16 -1 (5175 3100)(5425 3100);
WIRE 16 -1 (5175 3150)(5425 3150);
WIRE 16 -1 (5425 3150)(5425 3100);
WIRE 16 -1 (5175 3200)(5425 3200);
WIRE 16 -1 (5425 3200)(5425 3150);
WIRE 16 -1 (5175 3250)(5425 3250);
WIRE 16 -1 (5425 3250)(5425 3200);
WIRE 16 -1 (5425 3300)(5175 3300);
WIRE 16 -1 (5425 3300)(5425 3250);
WIRE 16 -1 (5425 3350)(5175 3350);
WIRE 16 -1 (5425 3350)(5425 3300);
WIRE 16 -1 (5175 3400)(5425 3400);
WIRE 16 -1 (5425 3400)(5425 3350);
WIRE 16 -1 (5175 3450)(5425 3450);
WIRE 16 -1 (5425 3450)(5425 3400);
WIRE 16 -1 (5175 3500)(5425 3500);
WIRE 16 -1 (5425 3450)(5425 3500);
WIRE 16 -1 (5175 3550)(5425 3550);
WIRE 16 -1 (5425 3550)(5425 3500);
WIRE 16 -1 (5425 3600)(5425 3550);
WIRE 16 -1 (5175 3600)(5425 3600);
WIRE 16 -1 (5175 3650)(5425 3650);
WIRE 16 -1 (5425 3650)(5425 3600);
WIRE 16 -1 (5175 3700)(5425 3700);
WIRE 16 -1 (5425 3700)(5425 3650);
WIRE 16 -1 (5175 3750)(5425 3750);
WIRE 16 -1 (5425 3750)(5425 3700);
WIRE 16 -1 (5175 3800)(5425 3800);
WIRE 16 -1 (5425 3800)(5425 3750);
WIRE 16 -1 (5175 3850)(5425 3850);
WIRE 16 -1 (5425 3850)(5425 3800);
WIRE 16 -1 (5175 3900)(5425 3900);
WIRE 16 -1 (5425 3900)(5425 3850);
WIRE 16 -1 (5175 3950)(5425 3950);
WIRE 16 -1 (5425 3950)(5425 3900);
WIRE 16 -1 (5175 4000)(5425 4000);
WIRE 16 -1 (5425 4000)(5425 3950);
WIRE 16 -1 (5175 4050)(5425 4050);
WIRE 16 -1 (5425 4050)(5425 4000);
WIRE 16 -1 (5425 4100)(5425 4050);
WIRE 16 -1 (5175 4100)(5425 4100);
WIRE 16 -1 (5175 4150)(5425 4150);
WIRE 16 -1 (5425 4150)(5425 4100);
WIRE 16 -1 (5425 4200)(5425 4150);
WIRE 16 -1 (5175 4200)(5425 4200);
WIRE 16 -1 (-925 4200)(-750 4200);
WIRE 16 -1 (-2300 2800)(-2125 2800);
WIRE 16 -1 (-2300 2650)(-2125 2650);
WIRE 16 -1 (-2300 2500)(-2125 2500);
WIRE 16 -1 (-2300 2350)(-2125 2350);
WIRE 16 -1 (-2300 3900)(-2125 3900);
WIRE 16 -1 (-2300 3500)(-2125 3500);
WIRE 16 -1 (-2300 3950)(-2125 3950);
WIRE 16 -1 (-2300 3550)(-2125 3550);
WIRE 16 -1 (-2300 4000)(-2125 4000);
WIRE 16 -1 (-2300 3600)(-2125 3600);
WIRE 16 -1 (-2300 4050)(-2125 4050);
WIRE 16 -1 (-2300 3650)(-2125 3650);
WIRE 16 -1 (-2300 3700)(-2125 3700);
WIRE 16 -1 (-2300 3750)(-2125 3750);
WIRE 16 -1 (-2300 3800)(-2125 3800);
WIRE 16 -1 (-2300 2750)(-2125 2750);
WIRE 16 -1 (-2300 2600)(-2125 2600);
WIRE 16 -1 (-2300 2550)(-2125 2550);
WIRE 16 -1 (-2300 2300)(-2125 2300);
WIRE 16 -1 (-2300 2250)(-2125 2250);
WIRE 16 -1 (-2300 2200)(-2125 2200);
WIRE 16 -1 (-2300 2050)(-2125 2050);
WIRE 16 -1 (-2125 2900)(-3225 2900);
FORCEPROP 2 LAST SIG_NAME M_D_CPU0_CLK_DN<1>
J 0
(-3137 2909);
DISPLAY 0.680851 (-3137 2909);
PAINT WHITE (-3137 2909);
WIRE 16 -1 (-2125 2950)(-3225 2950);
FORCEPROP 2 LAST SIG_NAME M_D_CPU0_CLK_DP<1>
J 0
(-3137 2959);
DISPLAY 0.680851 (-3137 2959);
PAINT WHITE (-3137 2959);
WIRE 16 -1 (-2125 3200)(-3225 3200);
FORCEPROP 2 LAST SIG_NAME M_D_CPU0_SA_CS_N<2>
J 0
(-3137 3209);
DISPLAY 0.680851 (-3137 3209);
PAINT WHITE (-3137 3209);
WIRE 16 -1 (-2125 3050)(-3225 3050);
FORCEPROP 2 LAST SIG_NAME M_D_CPU0_SB_CS_N<2>
J 0
(-3137 3059);
DISPLAY 0.680851 (-3137 3059);
PAINT WHITE (-3137 3059);
WIRE 16 -1 (-2125 3250)(-3225 3250);
FORCEPROP 2 LAST SIG_NAME M_D_CPU0_SA_CS_N<3>
J 0
(-3137 3259);
DISPLAY 0.680851 (-3137 3259);
PAINT WHITE (-3137 3259);
WIRE 16 -1 (-2125 3100)(-3225 3100);
FORCEPROP 2 LAST SIG_NAME M_D_CPU0_SB_CS_N<3>
J 0
(-3137 3109);
DISPLAY 0.680851 (-3137 3109);
PAINT WHITE (-3137 3109);
WIRE 16 -1 (-925 4150)(-750 4150);
WIRE 16 -1 (-925 4100)(-750 4100);
WIRE 16 -1 (-925 4050)(-750 4050);
WIRE 16 -1 (-925 4000)(-750 4000);
WIRE 16 -1 (-925 3950)(-750 3950);
WIRE 16 -1 (-925 3900)(-750 3900);
WIRE 16 -1 (-925 3850)(-750 3850);
WIRE 16 -1 (-925 3800)(-750 3800);
WIRE 16 -1 (-925 3750)(-750 3750);
WIRE 16 -1 (-925 3700)(-750 3700);
WIRE 16 -1 (-925 3650)(-750 3650);
WIRE 16 -1 (-925 3600)(-750 3600);
WIRE 16 -1 (-925 3550)(-750 3550);
WIRE 16 -1 (-925 3500)(-750 3500);
WIRE 16 -1 (-925 3300)(-750 3300);
WIRE 16 -1 (-925 3250)(-750 3250);
WIRE 16 -1 (-925 3200)(-750 3200);
WIRE 16 -1 (-925 3150)(-750 3150);
WIRE 16 -1 (-925 3100)(-750 3100);
WIRE 16 -1 (-925 3050)(-750 3050);
WIRE 16 -1 (-925 3000)(-750 3000);
WIRE 16 -1 (-925 2950)(-750 2950);
WIRE 16 -1 (-925 2900)(-750 2900);
WIRE 16 -1 (-925 2850)(-750 2850);
WIRE 16 -1 (-925 2800)(-750 2800);
WIRE 16 -1 (-925 2750)(-750 2750);
WIRE 16 -1 (-925 2700)(-750 2700);
WIRE 16 -1 (-925 2650)(-750 2650);
WIRE 16 -1 (-925 2550)(-750 2550);
WIRE 16 -1 (-925 2500)(-750 2500);
WIRE 16 -1 (-925 2450)(-750 2450);
WIRE 16 -1 (-925 2400)(-750 2400);
WIRE 16 -1 (-925 2350)(-750 2350);
WIRE 16 -1 (-925 2300)(-750 2300);
WIRE 16 -1 (-925 2250)(-750 2250);
WIRE 16 -1 (-925 2200)(-750 2200);
WIRE 16 -1 (-925 2150)(-750 2150);
WIRE 16 -1 (-925 2100)(-750 2100);
WIRE 16 -1 (-925 2050)(-750 2050);
WIRE 16 -1 (-925 2000)(-750 2000);
WIRE 16 -1 (-925 1950)(-750 1950);
WIRE 16 -1 (-925 1900)(-750 1900);
WIRE 16 -1 (-925 1850)(-750 1850);
WIRE 16 -1 (-925 1800)(-750 1800);
WIRE 16 -1 (-925 1750)(-750 1750);
WIRE 16 -1 (-925 1700)(-750 1700);
WIRE 16 -1 (-925 1650)(-750 1650);
WIRE 16 -1 (-925 1550)(-750 1550);
WIRE 16 -1 (-925 1500)(-750 1500);
WIRE 16 -1 (-925 1450)(-750 1450);
WIRE 16 -1 (-925 1400)(-750 1400);
WIRE 16 -1 (-925 1350)(-750 1350);
WIRE 16 -1 (-925 1300)(-750 1300);
WIRE 16 -1 (-925 1250)(-750 1250);
WIRE 16 -1 (-925 1200)(-750 1200);
WIRE 16 -1 (-925 1150)(-750 1150);
WIRE 16 -1 (-925 1100)(-750 1100);
WIRE 16 -1 (-925 1050)(-750 1050);
WIRE 16 -1 (-925 1000)(-750 1000);
WIRE 16 -1 (-2125 800)(-3225 800);
FORCEPROP 2 LAST SIG_NAME M_D_CPU0_SA_RSP<1>
J 0
(-3137 809);
DISPLAY 0.680851 (-3137 809);
PAINT WHITE (-3137 809);
WIRE 16 -1 (-2125 750)(-3225 750);
FORCEPROP 2 LAST SIG_NAME M_D_CPU0_SB_RSP<1>
J 0
(-3137 759);
DISPLAY 0.680851 (-3137 759);
PAINT WHITE (-3137 759);
WIRE 16 -1 (-2125 3400)(-3225 3400);
FORCEPROP 2 LAST SIG_NAME M_D_CPU0_SA_PAR
J 0
(-3137 3409);
DISPLAY 0.680851 (-3137 3409);
PAINT WHITE (-3137 3409);
WIRE 16 -1 (-2125 3350)(-3225 3350);
FORCEPROP 2 LAST SIG_NAME M_D_CPU0_SB_PAR
J 0
(-3137 3359);
DISPLAY 0.680851 (-3137 3359);
PAINT WHITE (-3137 3359);
WIRE 16 -1 (-2125 1150)(-3225 1150);
FORCEPROP 2 LAST SIG_NAME TP_CHD_CPU0_DIMM2_FRU_4
J 0
(-3137 1159);
DISPLAY 0.680851 (-3137 1159);
PAINT WHITE (-3137 1159);
WIRE 16 -1 (-2125 1100)(-3225 1100);
FORCEPROP 2 LAST SIG_NAME TP_CHD_CPU0_DIMM2_FRU_3
J 0
(-3137 1109);
DISPLAY 0.680851 (-3137 1109);
PAINT WHITE (-3137 1109);
WIRE 16 -1 (-2125 1050)(-3225 1050);
FORCEPROP 2 LAST SIG_NAME TP_CHD_CPU0_DIMM2_FRU_2
J 0
(-3137 1059);
DISPLAY 0.680851 (-3137 1059);
PAINT WHITE (-3137 1059);
WIRE 16 -1 (-2125 1000)(-3225 1000);
FORCEPROP 2 LAST SIG_NAME TP_CHD_CPU0_DIMM2_FRU_1
J 0
(-3137 1009);
DISPLAY 0.680851 (-3137 1009);
PAINT WHITE (-3137 1009);
WIRE 16 -1 (-2125 950)(-3225 950);
FORCEPROP 2 LAST SIG_NAME TP_CHD_CPU0_DIMM2_FRU_0
J 0
(-3137 959);
DISPLAY 0.680851 (-3137 959);
PAINT WHITE (-3137 959);
WIRE 16 -1 (-925 1600)(-750 1600);
WIRE 16 -1 (-925 3450)(-750 3450);
WIRE 16 -1 (-925 3350)(-750 3350);
WIRE 16 -1 (3975 4050)(3725 4050);
WIRE 16 -1 (3725 4000)(3725 4050);
WIRE 16 -1 (3725 4000)(3975 4000);
WIRE 16 -1 (3725 3950)(3725 4000);
WIRE 16 -1 (3975 3950)(3725 3950);
WIRE 16 -1 (3725 3900)(3725 3950);
WIRE 16 -1 (3725 3900)(3975 3900);
WIRE 16 -1 (3725 3850)(3725 3900);
WIRE 16 -1 (3725 3850)(3975 3850);
WIRE 16 -1 (3725 3800)(3725 3850);
WIRE 16 -1 (3725 3800)(3975 3800);
WIRE 16 -1 (3725 3750)(3725 3800);
WIRE 16 -1 (3725 3750)(3975 3750);
WIRE 16 -1 (3725 3700)(3725 3750);
WIRE 16 -1 (3725 3700)(3975 3700);
WIRE 16 -1 (3725 3650)(3725 3700);
WIRE 16 -1 (3725 3650)(3975 3650);
WIRE 16 -1 (3725 3600)(3725 3650);
WIRE 16 -1 (3725 3600)(3975 3600);
WIRE 16 -1 (3725 3550)(3975 3550);
WIRE 16 -1 (3725 3550)(3725 3600);
WIRE 16 -1 (3725 3500)(3725 3550);
WIRE 16 -1 (3725 3500)(3975 3500);
WIRE 16 -1 (3725 3450)(3725 3500);
WIRE 16 -1 (3975 3450)(3725 3450);
WIRE 16 -1 (3725 3400)(3725 3450);
WIRE 16 -1 (3725 3400)(3975 3400);
WIRE 16 -1 (3725 3350)(3725 3400);
WIRE 16 -1 (3725 3350)(3975 3350);
WIRE 16 -1 (3725 3300)(3725 3350);
WIRE 16 -1 (3725 3300)(3975 3300);
WIRE 16 -1 (3725 3250)(3725 3300);
WIRE 16 -1 (3725 3250)(3975 3250);
WIRE 16 -1 (3725 3200)(3725 3250);
WIRE 16 -1 (3725 3200)(3975 3200);
WIRE 16 -1 (3725 3150)(3725 3200);
WIRE 16 -1 (3725 3150)(3975 3150);
WIRE 16 -1 (3725 3100)(3725 3150);
WIRE 16 -1 (3725 3100)(3975 3100);
WIRE 16 -1 (3725 3050)(3975 3050);
WIRE 16 -1 (3725 3050)(3725 3100);
WIRE 16 -1 (3725 3000)(3725 3050);
WIRE 16 -1 (3725 3000)(3975 3000);
WIRE 16 -1 (3725 2950)(3725 3000);
WIRE 16 -1 (3975 2950)(3725 2950);
WIRE 16 -1 (3725 2900)(3725 2950);
WIRE 16 -1 (3725 2900)(3975 2900);
WIRE 16 -1 (3725 2850)(3725 2900);
WIRE 16 -1 (3725 2850)(3975 2850);
WIRE 16 -1 (3725 2800)(3725 2850);
WIRE 16 -1 (3725 2800)(3975 2800);
WIRE 16 -1 (3725 2750)(3725 2800);
WIRE 16 -1 (3725 2750)(3975 2750);
WIRE 16 -1 (3725 2700)(3725 2750);
WIRE 16 -1 (3725 2700)(3975 2700);
WIRE 16 -1 (3725 2650)(3725 2700);
WIRE 16 -1 (3725 2650)(3975 2650);
WIRE 16 -1 (3725 2600)(3725 2650);
WIRE 16 -1 (3725 2600)(3975 2600);
WIRE 16 -1 (3725 2550)(3975 2550);
WIRE 16 -1 (3725 2550)(3725 2600);
WIRE 16 -1 (3725 2500)(3725 2550);
WIRE 16 -1 (3725 2500)(3975 2500);
WIRE 16 -1 (3725 2450)(3725 2500);
WIRE 16 -1 (3975 2450)(3725 2450);
WIRE 16 -1 (3725 2400)(3725 2450);
WIRE 16 -1 (3725 2400)(3975 2400);
WIRE 16 -1 (3725 2350)(3725 2400);
WIRE 16 -1 (3725 2350)(3975 2350);
WIRE 16 -1 (3725 2300)(3725 2350);
WIRE 16 -1 (3725 2300)(3975 2300);
WIRE 16 -1 (3725 2250)(3725 2300);
WIRE 16 -1 (3725 2250)(3975 2250);
WIRE 16 -1 (3725 2200)(3725 2250);
WIRE 16 -1 (3725 2200)(3975 2200);
WIRE 16 -1 (3725 2150)(3725 2200);
WIRE 16 -1 (3725 2150)(3975 2150);
WIRE 16 -1 (3725 2100)(3725 2150);
WIRE 16 -1 (3725 2100)(3975 2100);
WIRE 16 -1 (3725 2050)(3725 2100);
WIRE 16 -1 (3725 2050)(3975 2050);
WIRE 16 -1 (3725 2000)(3975 2000);
WIRE 16 -1 (3725 2000)(3725 2050);
WIRE 16 -1 (3725 1950)(3725 2000);
WIRE 16 -1 (3975 1950)(3725 1950);
WIRE 16 -1 (3725 1900)(3725 1950);
WIRE 16 -1 (3725 1900)(3975 1900);
WIRE 16 -1 (3725 1850)(3725 1900);
WIRE 16 -1 (3725 1850)(3975 1850);
WIRE 16 -1 (3725 1800)(3725 1850);
WIRE 16 -1 (3725 1800)(3975 1800);
WIRE 16 -1 (3725 1750)(3725 1800);
WIRE 16 -1 (3725 1750)(3975 1750);
WIRE 16 -1 (3725 1700)(3725 1750);
WIRE 16 -1 (3725 1700)(3975 1700);
WIRE 16 -1 (3725 1650)(3725 1700);
WIRE 16 -1 (3725 1650)(3975 1650);
WIRE 16 -1 (3725 1600)(3725 1650);
WIRE 16 -1 (3725 1600)(3975 1600);
WIRE 16 -1 (3725 1550)(3725 1600);
WIRE 16 -1 (3725 1550)(3975 1550);
WIRE 16 -1 (3725 1500)(3975 1500);
WIRE 16 -1 (3725 1500)(3725 1550);
WIRE 16 -1 (3725 1450)(3725 1500);
WIRE 16 -1 (3975 1450)(3725 1450);
WIRE 16 -1 (3725 1400)(3725 1450);
WIRE 16 -1 (3725 1400)(3975 1400);
WIRE 16 -1 (3725 1350)(3725 1400);
WIRE 16 -1 (3725 1350)(3975 1350);
WIRE 16 -1 (3725 1300)(3725 1350);
WIRE 16 -1 (3725 1300)(3975 1300);
WIRE 16 -1 (3725 1250)(3725 1300);
WIRE 16 -1 (3725 1250)(3975 1250);
WIRE 16 -1 (3725 1200)(3725 1250);
WIRE 16 -1 (3725 1200)(3975 1200);
WIRE 16 -1 (3725 1150)(3725 1200);
WIRE 16 -1 (3725 1150)(3975 1150);
WIRE 16 -1 (3725 1100)(3725 1150);
WIRE 16 -1 (3725 1100)(3975 1100);
WIRE 16 -1 (3725 1050)(3725 1100);
WIRE 16 -1 (3725 1050)(3975 1050);
WIRE 16 -1 (3725 1000)(3975 1000);
WIRE 16 -1 (3725 1000)(3725 1050);
WIRE 16 -1 (3725 950)(3725 1000);
WIRE 16 -1 (3725 950)(3975 950);
WIRE 16 -1 (-925 3400)(-750 3400);
WIRE 16 -1 (-2300 4100)(-2125 4100);
WIRE 16 -1 (-2300 4150)(-2125 4150);
WIRE 16 -1 (-2300 4200)(-2125 4200);
WIRE 16 -1 (3975 4100)(3725 4100);
WIRE 16 -1 (3725 4150)(3725 4100);
WIRE 16 -1 (3725 4150)(3975 4150);
WIRE 16 -1 (3725 4200)(3725 4150);
WIRE 16 -1 (3975 4200)(3725 4200);
WIRE 16 -1 (-2300 2700)(-2125 2700);
WIRE 16 -1 (-2300 2150)(-2125 2150);
DOT 1 (5425 850);
DOT 1 (5425 900);
DOT 1 (5425 950);
DOT 1 (5425 4150);
DOT 1 (5425 4100);
DOT 1 (5425 4000);
DOT 1 (5425 4050);
DOT 1 (5425 3950);
DOT 1 (5425 3900);
DOT 1 (5425 3850);
DOT 1 (5425 3750);
DOT 1 (5425 3800);
DOT 1 (5425 3700);
DOT 1 (5425 3650);
DOT 1 (5425 3600);
DOT 1 (5425 3500);
DOT 1 (5425 3550);
DOT 1 (5425 3450);
DOT 1 (5425 3400);
DOT 1 (5425 3350);
DOT 1 (5425 3250);
DOT 1 (5425 3300);
DOT 1 (5425 3200);
DOT 1 (5425 3150);
DOT 1 (5425 3100);
DOT 1 (5425 3050);
DOT 1 (5425 3000);
DOT 1 (5425 2950);
DOT 1 (5425 2850);
DOT 1 (5425 2900);
DOT 1 (5425 2800);
DOT 1 (5425 2750);
DOT 1 (5425 2700);
DOT 1 (5425 2650);
DOT 1 (5425 2600);
DOT 1 (5425 2550);
DOT 1 (5425 2500);
DOT 1 (5425 2450);
DOT 1 (5425 2350);
DOT 1 (5425 2400);
DOT 1 (5425 2300);
DOT 1 (5425 2250);
DOT 1 (5425 2200);
DOT 1 (5425 2150);
DOT 1 (5425 2100);
DOT 1 (5425 2050);
DOT 1 (5425 2000);
DOT 1 (5425 1950);
DOT 1 (5425 1900);
DOT 1 (5425 1850);
DOT 1 (5425 1800);
DOT 1 (5425 1700);
DOT 1 (5425 1750);
DOT 1 (5425 1650);
DOT 1 (5425 1600);
DOT 1 (5425 1550);
DOT 1 (5425 1500);
DOT 1 (5425 1450);
DOT 1 (5425 1400);
DOT 1 (5425 1350);
DOT 1 (5425 1300);
DOT 1 (5425 1200);
DOT 1 (5425 1250);
DOT 1 (5425 1150);
DOT 1 (5425 1100);
DOT 1 (5425 1050);
DOT 1 (3725 4200);
DOT 1 (3725 4150);
DOT 1 (3725 4000);
DOT 1 (3725 3900);
DOT 1 (3725 3850);
DOT 1 (3725 3700);
DOT 1 (3725 3650);
DOT 1 (3725 3750);
DOT 1 (3725 3600);
DOT 1 (3725 3800);
DOT 1 (3725 3450);
DOT 1 (3725 3400);
DOT 1 (3725 3500);
DOT 1 (3725 3550);
DOT 1 (3725 3200);
DOT 1 (3725 3300);
DOT 1 (3725 3150);
DOT 1 (3725 3100);
DOT 1 (3725 3000);
DOT 1 (3725 2900);
DOT 1 (3725 2950);
DOT 1 (3725 2850);
DOT 1 (3725 2750);
DOT 1 (3725 2650);
DOT 1 (3725 2700);
DOT 1 (3725 2600);
DOT 1 (3725 2800);
DOT 1 (3725 2500);
DOT 1 (3725 2450);
DOT 1 (3725 2400);
DOT 1 (3725 2350);
DOT 1 (3725 2550);
DOT 1 (3725 2200);
DOT 1 (3725 2300);
DOT 1 (3725 2150);
DOT 1 (3725 2100);
DOT 1 (3725 2050);
DOT 1 (3725 2000);
DOT 1 (3725 1900);
DOT 1 (3725 1950);
DOT 1 (3725 1850);
DOT 1 (3725 1800);
DOT 1 (3725 1650);
DOT 1 (3725 1600);
DOT 1 (3725 1700);
DOT 1 (3725 1550);
DOT 1 (3725 1750);
DOT 1 (3725 1450);
DOT 1 (3725 1400);
DOT 1 (3725 1350);
DOT 1 (3725 1300);
DOT 1 (3725 1500);
DOT 1 (3725 1150);
DOT 1 (3725 1200);
DOT 1 (3725 1100);
DOT 1 (3725 1050);
DOT 1 (3725 1250);
DOT 1 (3725 1000);
DOT 1 (3725 950);
DOT 1 (2025 550);
DOT 1 (2650 75);
DOT 1 (3725 3050);
DOT 1 (3725 3950);
DOT 1 (3725 3250);
DOT 1 (3725 2250);
DOT 1 (3725 3350);
FORCENOTE
20210728 MODIFY FOR GT
(-3625 4875) 0;
DISPLAY LEFT (-3625 4875);
DISPLAY 2.510638 (-3625 4875);
PAINT PINK (-3625 4875);
QUIT
